(kicad_sch
	(version 20250114)
	(generator "eeschema")
	(generator_version "9.0")
	(paper "A3")
	(title_block
		(title "Artix - Datacenter Secure Control Module (DC-SCM)")
		(date "2024-11-06")
		(rev "1.1.3")
	)
	(text "VLDOIN"
		(exclude_from_sim no)
		(at 112.395 221.615 0)
		(effects
			(font
				(size 1.27 1.27)
			)
			(justify right bottom)
		)
	)
	(junction
		(at 162.56 52.07)
		(diameter 0)
		(color 0 0 0 0)
	)
	(junction
		(at 185.42 38.1)
		(diameter 0)
		(color 0 0 0 0)
	)
	(junction
		(at 220.98 220.98)
		(diameter 0)
		(color 0 0 0 0)
	)
	(junction
		(at 220.98 248.92)
		(diameter 0)
		(color 0 0 0 0)
	)
	(junction
		(at 147.32 59.69)
		(diameter 0)
		(color 0 0 0 0)
	)
	(junction
		(at 170.18 219.71)
		(diameter 0)
		(color 0 0 0 0)
	)
	(junction
		(at 220.98 256.54)
		(diameter 0)
		(color 0 0 0 0)
	)
	(junction
		(at 220.98 228.6)
		(diameter 0)
		(color 0 0 0 0)
	)
	(junction
		(at 220.98 213.36)
		(diameter 0)
		(color 0 0 0 0)
	)
	(junction
		(at 107.95 185.42)
		(diameter 0)
		(color 0 0 0 0)
	)
	(junction
		(at 105.41 204.47)
		(diameter 0)
		(color 0 0 0 0)
	)
	(junction
		(at 243.84 59.69)
		(diameter 0)
		(color 0 0 0 0)
	)
	(junction
		(at 154.94 45.72)
		(diameter 0)
		(color 0 0 0 0)
	)
	(junction
		(at 130.81 38.1)
		(diameter 0)
		(color 0 0 0 0)
	)
	(junction
		(at 177.8 52.07)
		(diameter 0)
		(color 0 0 0 0)
	)
	(junction
		(at 220.98 241.3)
		(diameter 0)
		(color 0 0 0 0)
	)
	(junction
		(at 191.77 38.1)
		(diameter 0)
		(color 0 0 0 0)
	)
	(junction
		(at 154.94 52.07)
		(diameter 0)
		(color 0 0 0 0)
	)
	(junction
		(at 220.98 254)
		(diameter 0)
		(color 0 0 0 0)
	)
	(junction
		(at 170.18 45.72)
		(diameter 0)
		(color 0 0 0 0)
	)
	(junction
		(at 220.98 205.74)
		(diameter 0)
		(color 0 0 0 0)
	)
	(junction
		(at 162.56 195.58)
		(diameter 0)
		(color 0 0 0 0)
	)
	(junction
		(at 147.32 38.1)
		(diameter 0)
		(color 0 0 0 0)
	)
	(junction
		(at 147.32 52.07)
		(diameter 0)
		(color 0 0 0 0)
	)
	(junction
		(at 162.56 38.1)
		(diameter 0)
		(color 0 0 0 0)
	)
	(junction
		(at 177.8 195.58)
		(diameter 0)
		(color 0 0 0 0)
	)
	(junction
		(at 114.3 212.09)
		(diameter 0)
		(color 0 0 0 0)
	)
	(junction
		(at 139.7 52.07)
		(diameter 0)
		(color 0 0 0 0)
	)
	(junction
		(at 220.98 210.82)
		(diameter 0)
		(color 0 0 0 0)
	)
	(junction
		(at 170.18 38.1)
		(diameter 0)
		(color 0 0 0 0)
	)
	(junction
		(at 220.98 231.14)
		(diameter 0)
		(color 0 0 0 0)
	)
	(junction
		(at 170.18 203.2)
		(diameter 0)
		(color 0 0 0 0)
	)
	(junction
		(at 152.4 195.58)
		(diameter 0)
		(color 0 0 0 0)
	)
	(junction
		(at 123.19 38.1)
		(diameter 0)
		(color 0 0 0 0)
	)
	(junction
		(at 220.98 243.84)
		(diameter 0)
		(color 0 0 0 0)
	)
	(junction
		(at 154.94 59.69)
		(diameter 0)
		(color 0 0 0 0)
	)
	(junction
		(at 238.76 143.51)
		(diameter 0)
		(color 0 0 0 0)
	)
	(junction
		(at 220.98 226.06)
		(diameter 0)
		(color 0 0 0 0)
	)
	(junction
		(at 170.18 52.07)
		(diameter 0)
		(color 0 0 0 0)
	)
	(junction
		(at 220.98 251.46)
		(diameter 0)
		(color 0 0 0 0)
	)
	(junction
		(at 139.7 45.72)
		(diameter 0)
		(color 0 0 0 0)
	)
	(junction
		(at 252.73 52.07)
		(diameter 0)
		(color 0 0 0 0)
	)
	(junction
		(at 162.56 45.72)
		(diameter 0)
		(color 0 0 0 0)
	)
	(junction
		(at 185.42 203.2)
		(diameter 0)
		(color 0 0 0 0)
	)
	(junction
		(at 147.32 45.72)
		(diameter 0)
		(color 0 0 0 0)
	)
	(junction
		(at 139.7 38.1)
		(diameter 0)
		(color 0 0 0 0)
	)
	(junction
		(at 170.18 59.69)
		(diameter 0)
		(color 0 0 0 0)
	)
	(junction
		(at 220.98 203.2)
		(diameter 0)
		(color 0 0 0 0)
	)
	(junction
		(at 238.76 146.05)
		(diameter 0)
		(color 0 0 0 0)
	)
	(junction
		(at 114.3 222.25)
		(diameter 0)
		(color 0 0 0 0)
	)
	(junction
		(at 154.94 38.1)
		(diameter 0)
		(color 0 0 0 0)
	)
	(junction
		(at 177.8 38.1)
		(diameter 0)
		(color 0 0 0 0)
	)
	(junction
		(at 243.84 52.07)
		(diameter 0)
		(color 0 0 0 0)
	)
	(junction
		(at 185.42 195.58)
		(diameter 0)
		(color 0 0 0 0)
	)
	(junction
		(at 220.98 200.66)
		(diameter 0)
		(color 0 0 0 0)
	)
	(junction
		(at 220.98 198.12)
		(diameter 0)
		(color 0 0 0 0)
	)
	(junction
		(at 177.8 45.72)
		(diameter 0)
		(color 0 0 0 0)
	)
	(junction
		(at 220.98 236.22)
		(diameter 0)
		(color 0 0 0 0)
	)
	(junction
		(at 123.19 185.42)
		(diameter 0)
		(color 0 0 0 0)
	)
	(junction
		(at 238.76 59.69)
		(diameter 0)
		(color 0 0 0 0)
	)
	(junction
		(at 220.98 223.52)
		(diameter 0)
		(color 0 0 0 0)
	)
	(junction
		(at 220.98 218.44)
		(diameter 0)
		(color 0 0 0 0)
	)
	(junction
		(at 170.18 212.09)
		(diameter 0)
		(color 0 0 0 0)
	)
	(junction
		(at 185.42 45.72)
		(diameter 0)
		(color 0 0 0 0)
	)
	(junction
		(at 220.98 195.58)
		(diameter 0)
		(color 0 0 0 0)
	)
	(junction
		(at 130.81 45.72)
		(diameter 0)
		(color 0 0 0 0)
	)
	(junction
		(at 220.98 208.28)
		(diameter 0)
		(color 0 0 0 0)
	)
	(junction
		(at 114.3 185.42)
		(diameter 0)
		(color 0 0 0 0)
	)
	(junction
		(at 220.98 246.38)
		(diameter 0)
		(color 0 0 0 0)
	)
	(junction
		(at 162.56 212.09)
		(diameter 0)
		(color 0 0 0 0)
	)
	(junction
		(at 139.7 59.69)
		(diameter 0)
		(color 0 0 0 0)
	)
	(junction
		(at 101.6 91.44)
		(diameter 0)
		(color 0 0 0 0)
	)
	(junction
		(at 220.98 233.68)
		(diameter 0)
		(color 0 0 0 0)
	)
	(junction
		(at 162.56 59.69)
		(diameter 0)
		(color 0 0 0 0)
	)
	(junction
		(at 114.3 204.47)
		(diameter 0)
		(color 0 0 0 0)
	)
	(junction
		(at 177.8 203.2)
		(diameter 0)
		(color 0 0 0 0)
	)
	(junction
		(at 170.18 195.58)
		(diameter 0)
		(color 0 0 0 0)
	)
	(wire
		(pts
			(xy 228.6 246.38) (xy 220.98 246.38)
		)
		(stroke
			(width 0)
			(type default)
		)
	)
	(wire
		(pts
			(xy 228.6 200.66) (xy 220.98 200.66)
		)
		(stroke
			(width 0)
			(type default)
		)
	)
	(wire
		(pts
			(xy 246.38 107.95) (xy 236.22 107.95)
		)
		(stroke
			(width 0)
			(type default)
		)
	)
	(wire
		(pts
			(xy 200.66 87.63) (xy 190.5 87.63)
		)
		(stroke
			(width 0)
			(type default)
		)
	)
	(wire
		(pts
			(xy 238.76 142.24) (xy 238.76 143.51)
		)
		(stroke
			(width 0)
			(type default)
		)
	)
	(wire
		(pts
			(xy 151.13 207.01) (xy 151.13 212.09)
		)
		(stroke
			(width 0)
			(type default)
		)
	)
	(wire
		(pts
			(xy 185.42 45.72) (xy 185.42 44.45)
		)
		(stroke
			(width 0)
			(type default)
		)
	)
	(wire
		(pts
			(xy 147.32 38.1) (xy 154.94 38.1)
		)
		(stroke
			(width 0)
			(type default)
		)
	)
	(wire
		(pts
			(xy 162.56 59.69) (xy 170.18 59.69)
		)
		(stroke
			(width 0)
			(type default)
		)
	)
	(wire
		(pts
			(xy 147.32 45.72) (xy 154.94 45.72)
		)
		(stroke
			(width 0)
			(type default)
		)
	)
	(wire
		(pts
			(xy 101.6 93.98) (xy 101.6 91.44)
		)
		(stroke
			(width 0)
			(type default)
		)
	)
	(wire
		(pts
			(xy 240.03 210.82) (xy 233.68 210.82)
		)
		(stroke
			(width 0)
			(type default)
		)
	)
	(wire
		(pts
			(xy 170.18 212.09) (xy 170.18 213.36)
		)
		(stroke
			(width 0)
			(type default)
		)
	)
	(wire
		(pts
			(xy 190.5 67.31) (xy 200.66 67.31)
		)
		(stroke
			(width 0)
			(type default)
		)
	)
	(wire
		(pts
			(xy 162.56 52.07) (xy 170.18 52.07)
		)
		(stroke
			(width 0)
			(type default)
		)
	)
	(wire
		(pts
			(xy 243.84 59.69) (xy 243.84 60.96)
		)
		(stroke
			(width 0)
			(type default)
		)
	)
	(wire
		(pts
			(xy 162.56 212.09) (xy 162.56 213.36)
		)
		(stroke
			(width 0)
			(type default)
		)
	)
	(wire
		(pts
			(xy 105.41 210.82) (xy 105.41 212.09)
		)
		(stroke
			(width 0)
			(type default)
		)
	)
	(wire
		(pts
			(xy 114.3 204.47) (xy 129.54 204.47)
		)
		(stroke
			(width 0)
			(type default)
		)
	)
	(wire
		(pts
			(xy 105.41 204.47) (xy 105.41 205.74)
		)
		(stroke
			(width 0)
			(type default)
		)
	)
	(wire
		(pts
			(xy 236.22 80.01) (xy 246.38 80.01)
		)
		(stroke
			(width 0)
			(type default)
		)
	)
	(wire
		(pts
			(xy 243.84 52.07) (xy 252.73 52.07)
		)
		(stroke
			(width 0)
			(type default)
		)
	)
	(wire
		(pts
			(xy 246.38 113.03) (xy 236.22 113.03)
		)
		(stroke
			(width 0)
			(type default)
		)
	)
	(wire
		(pts
			(xy 220.98 200.66) (xy 220.98 203.2)
		)
		(stroke
			(width 0)
			(type default)
		)
	)
	(wire
		(pts
			(xy 220.98 256.54) (xy 228.6 256.54)
		)
		(stroke
			(width 0)
			(type default)
		)
	)
	(wire
		(pts
			(xy 170.18 195.58) (xy 170.18 196.85)
		)
		(stroke
			(width 0)
			(type default)
		)
	)
	(wire
		(pts
			(xy 190.5 123.19) (xy 200.66 123.19)
		)
		(stroke
			(width 0)
			(type default)
		)
	)
	(wire
		(pts
			(xy 246.38 118.11) (xy 236.22 118.11)
		)
		(stroke
			(width 0)
			(type default)
		)
	)
	(wire
		(pts
			(xy 114.3 200.66) (xy 129.54 200.66)
		)
		(stroke
			(width 0)
			(type default)
		)
	)
	(wire
		(pts
			(xy 233.68 203.2) (xy 240.03 203.2)
		)
		(stroke
			(width 0)
			(type default)
		)
	)
	(wire
		(pts
			(xy 220.98 236.22) (xy 220.98 241.3)
		)
		(stroke
			(width 0)
			(type default)
		)
	)
	(wire
		(pts
			(xy 139.7 44.45) (xy 139.7 45.72)
		)
		(stroke
			(width 0)
			(type default)
		)
	)
	(wire
		(pts
			(xy 170.18 52.07) (xy 177.8 52.07)
		)
		(stroke
			(width 0)
			(type default)
		)
	)
	(wire
		(pts
			(xy 220.98 208.28) (xy 220.98 210.82)
		)
		(stroke
			(width 0)
			(type default)
		)
	)
	(wire
		(pts
			(xy 128.27 185.42) (xy 128.27 195.58)
		)
		(stroke
			(width 0)
			(type default)
		)
	)
	(wire
		(pts
			(xy 185.42 195.58) (xy 185.42 196.85)
		)
		(stroke
			(width 0)
			(type default)
		)
	)
	(wire
		(pts
			(xy 246.38 100.33) (xy 236.22 100.33)
		)
		(stroke
			(width 0)
			(type default)
		)
	)
	(wire
		(pts
			(xy 170.18 52.07) (xy 170.18 53.34)
		)
		(stroke
			(width 0)
			(type default)
		)
	)
	(wire
		(pts
			(xy 240.03 236.22) (xy 233.68 236.22)
		)
		(stroke
			(width 0)
			(type default)
		)
	)
	(wire
		(pts
			(xy 246.38 97.79) (xy 236.22 97.79)
		)
		(stroke
			(width 0)
			(type default)
		)
	)
	(wire
		(pts
			(xy 185.42 45.72) (xy 191.77 45.72)
		)
		(stroke
			(width 0)
			(type default)
		)
	)
	(wire
		(pts
			(xy 190.5 74.93) (xy 200.66 74.93)
		)
		(stroke
			(width 0)
			(type default)
		)
	)
	(wire
		(pts
			(xy 233.68 256.54) (xy 240.03 256.54)
		)
		(stroke
			(width 0)
			(type default)
		)
	)
	(wire
		(pts
			(xy 238.76 135.89) (xy 236.22 135.89)
		)
		(stroke
			(width 0)
			(type default)
		)
	)
	(wire
		(pts
			(xy 190.5 97.79) (xy 200.66 97.79)
		)
		(stroke
			(width 0)
			(type default)
		)
	)
	(wire
		(pts
			(xy 220.98 226.06) (xy 220.98 228.6)
		)
		(stroke
			(width 0)
			(type default)
		)
	)
	(wire
		(pts
			(xy 185.42 38.1) (xy 191.77 38.1)
		)
		(stroke
			(width 0)
			(type default)
		)
	)
	(wire
		(pts
			(xy 139.7 52.07) (xy 147.32 52.07)
		)
		(stroke
			(width 0)
			(type default)
		)
	)
	(wire
		(pts
			(xy 228.6 208.28) (xy 220.98 208.28)
		)
		(stroke
			(width 0)
			(type default)
		)
	)
	(wire
		(pts
			(xy 228.6 213.36) (xy 220.98 213.36)
		)
		(stroke
			(width 0)
			(type default)
		)
	)
	(wire
		(pts
			(xy 170.18 38.1) (xy 177.8 38.1)
		)
		(stroke
			(width 0)
			(type default)
		)
	)
	(wire
		(pts
			(xy 238.76 135.89) (xy 238.76 137.16)
		)
		(stroke
			(width 0)
			(type default)
		)
	)
	(wire
		(pts
			(xy 130.81 45.72) (xy 139.7 45.72)
		)
		(stroke
			(width 0)
			(type default)
		)
	)
	(wire
		(pts
			(xy 177.8 195.58) (xy 170.18 195.58)
		)
		(stroke
			(width 0)
			(type default)
		)
	)
	(wire
		(pts
			(xy 228.6 228.6) (xy 220.98 228.6)
		)
		(stroke
			(width 0)
			(type default)
		)
	)
	(wire
		(pts
			(xy 154.94 44.45) (xy 154.94 45.72)
		)
		(stroke
			(width 0)
			(type default)
		)
	)
	(wire
		(pts
			(xy 246.38 69.85) (xy 236.22 69.85)
		)
		(stroke
			(width 0)
			(type default)
		)
	)
	(wire
		(pts
			(xy 220.98 233.68) (xy 220.98 236.22)
		)
		(stroke
			(width 0)
			(type default)
		)
	)
	(wire
		(pts
			(xy 170.18 212.09) (xy 177.8 212.09)
		)
		(stroke
			(width 0)
			(type default)
		)
	)
	(wire
		(pts
			(xy 177.8 38.1) (xy 185.42 38.1)
		)
		(stroke
			(width 0)
			(type default)
		)
	)
	(wire
		(pts
			(xy 240.03 248.92) (xy 233.68 248.92)
		)
		(stroke
			(width 0)
			(type default)
		)
	)
	(wire
		(pts
			(xy 238.76 62.23) (xy 236.22 62.23)
		)
		(stroke
			(width 0)
			(type default)
		)
	)
	(wire
		(pts
			(xy 220.98 210.82) (xy 228.6 210.82)
		)
		(stroke
			(width 0)
			(type default)
		)
	)
	(wire
		(pts
			(xy 238.76 59.69) (xy 238.76 62.23)
		)
		(stroke
			(width 0)
			(type default)
		)
	)
	(wire
		(pts
			(xy 190.5 140.97) (xy 200.66 140.97)
		)
		(stroke
			(width 0)
			(type default)
		)
	)
	(wire
		(pts
			(xy 252.73 52.07) (xy 252.73 53.34)
		)
		(stroke
			(width 0)
			(type default)
		)
	)
	(wire
		(pts
			(xy 246.38 72.39) (xy 236.22 72.39)
		)
		(stroke
			(width 0)
			(type default)
		)
	)
	(wire
		(pts
			(xy 191.77 38.1) (xy 198.12 38.1)
		)
		(stroke
			(width 0)
			(type default)
		)
	)
	(wire
		(pts
			(xy 162.56 38.1) (xy 162.56 39.37)
		)
		(stroke
			(width 0)
			(type default)
		)
	)
	(wire
		(pts
			(xy 123.19 38.1) (xy 130.81 38.1)
		)
		(stroke
			(width 0)
			(type default)
		)
	)
	(wire
		(pts
			(xy 243.84 52.07) (xy 243.84 53.34)
		)
		(stroke
			(width 0)
			(type default)
		)
	)
	(wire
		(pts
			(xy 156.21 212.09) (xy 162.56 212.09)
		)
		(stroke
			(width 0)
			(type default)
		)
	)
	(wire
		(pts
			(xy 185.42 203.2) (xy 185.42 204.47)
		)
		(stroke
			(width 0)
			(type default)
		)
	)
	(wire
		(pts
			(xy 220.98 223.52) (xy 228.6 223.52)
		)
		(stroke
			(width 0)
			(type default)
		)
	)
	(wire
		(pts
			(xy 101.6 88.9) (xy 101.6 91.44)
		)
		(stroke
			(width 0)
			(type default)
		)
	)
	(wire
		(pts
			(xy 190.5 77.47) (xy 200.66 77.47)
		)
		(stroke
			(width 0)
			(type default)
		)
	)
	(wire
		(pts
			(xy 177.8 38.1) (xy 177.8 39.37)
		)
		(stroke
			(width 0)
			(type default)
		)
	)
	(wire
		(pts
			(xy 107.95 185.42) (xy 107.95 186.69)
		)
		(stroke
			(width 0)
			(type default)
		)
	)
	(wire
		(pts
			(xy 170.18 45.72) (xy 177.8 45.72)
		)
		(stroke
			(width 0)
			(type default)
		)
	)
	(wire
		(pts
			(xy 246.38 67.31) (xy 236.22 67.31)
		)
		(stroke
			(width 0)
			(type default)
		)
	)
	(wire
		(pts
			(xy 105.41 204.47) (xy 114.3 204.47)
		)
		(stroke
			(width 0)
			(type default)
		)
	)
	(wire
		(pts
			(xy 114.3 210.82) (xy 114.3 212.09)
		)
		(stroke
			(width 0)
			(type default)
		)
	)
	(wire
		(pts
			(xy 190.5 135.89) (xy 200.66 135.89)
		)
		(stroke
			(width 0)
			(type default)
		)
	)
	(wire
		(pts
			(xy 240.03 228.6) (xy 233.68 228.6)
		)
		(stroke
			(width 0)
			(type default)
		)
	)
	(wire
		(pts
			(xy 139.7 52.07) (xy 139.7 53.34)
		)
		(stroke
			(width 0)
			(type default)
		)
	)
	(wire
		(pts
			(xy 220.98 213.36) (xy 220.98 218.44)
		)
		(stroke
			(width 0)
			(type default)
		)
	)
	(wire
		(pts
			(xy 233.68 231.14) (xy 240.03 231.14)
		)
		(stroke
			(width 0)
			(type default)
		)
	)
	(wire
		(pts
			(xy 162.56 201.93) (xy 162.56 203.2)
		)
		(stroke
			(width 0)
			(type default)
		)
	)
	(wire
		(pts
			(xy 156.21 204.47) (xy 156.21 212.09)
		)
		(stroke
			(width 0)
			(type default)
		)
	)
	(wire
		(pts
			(xy 240.03 205.74) (xy 233.68 205.74)
		)
		(stroke
			(width 0)
			(type default)
		)
	)
	(wire
		(pts
			(xy 246.38 74.93) (xy 236.22 74.93)
		)
		(stroke
			(width 0)
			(type default)
		)
	)
	(wire
		(pts
			(xy 240.03 246.38) (xy 233.68 246.38)
		)
		(stroke
			(width 0)
			(type default)
		)
	)
	(wire
		(pts
			(xy 233.68 251.46) (xy 240.03 251.46)
		)
		(stroke
			(width 0)
			(type default)
		)
	)
	(wire
		(pts
			(xy 233.68 226.06) (xy 240.03 226.06)
		)
		(stroke
			(width 0)
			(type default)
		)
	)
	(wire
		(pts
			(xy 97.79 100.33) (xy 101.6 100.33)
		)
		(stroke
			(width 0)
			(type default)
		)
	)
	(wire
		(pts
			(xy 114.3 204.47) (xy 114.3 205.74)
		)
		(stroke
			(width 0)
			(type default)
		)
	)
	(wire
		(pts
			(xy 220.98 256.54) (xy 220.98 259.08)
		)
		(stroke
			(width 0)
			(type default)
		)
	)
	(wire
		(pts
			(xy 228.6 236.22) (xy 220.98 236.22)
		)
		(stroke
			(width 0)
			(type default)
		)
	)
	(wire
		(pts
			(xy 190.5 52.07) (xy 190.5 62.23)
		)
		(stroke
			(width 0)
			(type default)
		)
	)
	(wire
		(pts
			(xy 177.8 195.58) (xy 177.8 196.85)
		)
		(stroke
			(width 0)
			(type default)
		)
	)
	(wire
		(pts
			(xy 128.27 222.25) (xy 114.3 222.25)
		)
		(stroke
			(width 0)
			(type default)
		)
	)
	(wire
		(pts
			(xy 149.86 204.47) (xy 156.21 204.47)
		)
		(stroke
			(width 0)
			(type default)
		)
	)
	(wire
		(pts
			(xy 128.27 195.58) (xy 129.54 195.58)
		)
		(stroke
			(width 0)
			(type default)
		)
	)
	(wire
		(pts
			(xy 149.86 207.01) (xy 151.13 207.01)
		)
		(stroke
			(width 0)
			(type default)
		)
	)
	(wire
		(pts
			(xy 114.3 185.42) (xy 123.19 185.42)
		)
		(stroke
			(width 0)
			(type default)
		)
	)
	(wire
		(pts
			(xy 177.8 52.07) (xy 190.5 52.07)
		)
		(stroke
			(width 0)
			(type default)
		)
	)
	(wire
		(pts
			(xy 220.98 205.74) (xy 228.6 205.74)
		)
		(stroke
			(width 0)
			(type default)
		)
	)
	(wire
		(pts
			(xy 190.5 128.27) (xy 200.66 128.27)
		)
		(stroke
			(width 0)
			(type default)
		)
	)
	(wire
		(pts
			(xy 240.03 208.28) (xy 233.68 208.28)
		)
		(stroke
			(width 0)
			(type default)
		)
	)
	(wire
		(pts
			(xy 130.81 45.72) (xy 130.81 46.99)
		)
		(stroke
			(width 0)
			(type default)
		)
	)
	(wire
		(pts
			(xy 162.56 203.2) (xy 170.18 203.2)
		)
		(stroke
			(width 0)
			(type default)
		)
	)
	(wire
		(pts
			(xy 190.5 130.81) (xy 200.66 130.81)
		)
		(stroke
			(width 0)
			(type default)
		)
	)
	(wire
		(pts
			(xy 228.6 254) (xy 220.98 254)
		)
		(stroke
			(width 0)
			(type default)
		)
	)
	(wire
		(pts
			(xy 240.03 223.52) (xy 233.68 223.52)
		)
		(stroke
			(width 0)
			(type default)
		)
	)
	(wire
		(pts
			(xy 170.18 201.93) (xy 170.18 203.2)
		)
		(stroke
			(width 0)
			(type default)
		)
	)
	(wire
		(pts
			(xy 246.38 92.71) (xy 236.22 92.71)
		)
		(stroke
			(width 0)
			(type default)
		)
	)
	(wire
		(pts
			(xy 170.18 195.58) (xy 162.56 195.58)
		)
		(stroke
			(width 0)
			(type default)
		)
	)
	(wire
		(pts
			(xy 162.56 218.44) (xy 162.56 219.71)
		)
		(stroke
			(width 0)
			(type default)
		)
	)
	(wire
		(pts
			(xy 238.76 146.05) (xy 238.76 147.32)
		)
		(stroke
			(width 0)
			(type default)
		)
	)
	(wire
		(pts
			(xy 190.5 143.51) (xy 200.66 143.51)
		)
		(stroke
			(width 0)
			(type default)
		)
	)
	(wire
		(pts
			(xy 220.98 231.14) (xy 220.98 233.68)
		)
		(stroke
			(width 0)
			(type default)
		)
	)
	(wire
		(pts
			(xy 220.98 205.74) (xy 220.98 208.28)
		)
		(stroke
			(width 0)
			(type default)
		)
	)
	(wire
		(pts
			(xy 190.5 92.71) (xy 200.66 92.71)
		)
		(stroke
			(width 0)
			(type default)
		)
	)
	(wire
		(pts
			(xy 147.32 52.07) (xy 154.94 52.07)
		)
		(stroke
			(width 0)
			(type default)
		)
	)
	(wire
		(pts
			(xy 107.95 185.42) (xy 114.3 185.42)
		)
		(stroke
			(width 0)
			(type default)
		)
	)
	(wire
		(pts
			(xy 190.5 95.25) (xy 200.66 95.25)
		)
		(stroke
			(width 0)
			(type default)
		)
	)
	(wire
		(pts
			(xy 185.42 39.37) (xy 185.42 38.1)
		)
		(stroke
			(width 0)
			(type default)
		)
	)
	(wire
		(pts
			(xy 198.12 38.1) (xy 198.12 59.69)
		)
		(stroke
			(width 0)
			(type default)
		)
	)
	(wire
		(pts
			(xy 147.32 58.42) (xy 147.32 59.69)
		)
		(stroke
			(width 0)
			(type default)
		)
	)
	(wire
		(pts
			(xy 114.3 185.42) (xy 114.3 186.69)
		)
		(stroke
			(width 0)
			(type default)
		)
	)
	(wire
		(pts
			(xy 233.68 220.98) (xy 240.03 220.98)
		)
		(stroke
			(width 0)
			(type default)
		)
	)
	(wire
		(pts
			(xy 228.6 243.84) (xy 220.98 243.84)
		)
		(stroke
			(width 0)
			(type default)
		)
	)
	(wire
		(pts
			(xy 114.3 222.25) (xy 102.87 222.25)
		)
		(stroke
			(width 0)
			(type default)
		)
	)
	(wire
		(pts
			(xy 190.5 113.03) (xy 200.66 113.03)
		)
		(stroke
			(width 0)
			(type default)
		)
	)
	(wire
		(pts
			(xy 120.65 38.1) (xy 123.19 38.1)
		)
		(stroke
			(width 0)
			(type default)
		)
	)
	(wire
		(pts
			(xy 147.32 38.1) (xy 147.32 39.37)
		)
		(stroke
			(width 0)
			(type default)
		)
	)
	(wire
		(pts
			(xy 246.38 85.09) (xy 236.22 85.09)
		)
		(stroke
			(width 0)
			(type default)
		)
	)
	(wire
		(pts
			(xy 190.5 105.41) (xy 200.66 105.41)
		)
		(stroke
			(width 0)
			(type default)
		)
	)
	(wire
		(pts
			(xy 256.54 52.07) (xy 252.73 52.07)
		)
		(stroke
			(width 0)
			(type default)
		)
	)
	(wire
		(pts
			(xy 147.32 59.69) (xy 154.94 59.69)
		)
		(stroke
			(width 0)
			(type default)
		)
	)
	(wire
		(pts
			(xy 220.98 210.82) (xy 220.98 213.36)
		)
		(stroke
			(width 0)
			(type default)
		)
	)
	(wire
		(pts
			(xy 246.38 102.87) (xy 236.22 102.87)
		)
		(stroke
			(width 0)
			(type default)
		)
	)
	(wire
		(pts
			(xy 154.94 38.1) (xy 162.56 38.1)
		)
		(stroke
			(width 0)
			(type default)
		)
	)
	(wire
		(pts
			(xy 190.5 102.87) (xy 200.66 102.87)
		)
		(stroke
			(width 0)
			(type default)
		)
	)
	(wire
		(pts
			(xy 123.19 38.1) (xy 123.19 52.07)
		)
		(stroke
			(width 0)
			(type default)
		)
	)
	(wire
		(pts
			(xy 228.6 231.14) (xy 220.98 231.14)
		)
		(stroke
			(width 0)
			(type default)
		)
	)
	(wire
		(pts
			(xy 130.81 38.1) (xy 139.7 38.1)
		)
		(stroke
			(width 0)
			(type default)
		)
	)
	(wire
		(pts
			(xy 236.22 59.69) (xy 238.76 59.69)
		)
		(stroke
			(width 0)
			(type default)
		)
	)
	(wire
		(pts
			(xy 228.6 259.08) (xy 220.98 259.08)
		)
		(stroke
			(width 0)
			(type default)
		)
	)
	(wire
		(pts
			(xy 170.18 219.71) (xy 162.56 219.71)
		)
		(stroke
			(width 0)
			(type default)
		)
	)
	(wire
		(pts
			(xy 154.94 45.72) (xy 162.56 45.72)
		)
		(stroke
			(width 0)
			(type default)
		)
	)
	(wire
		(pts
			(xy 177.8 52.07) (xy 177.8 53.34)
		)
		(stroke
			(width 0)
			(type default)
		)
	)
	(wire
		(pts
			(xy 154.94 52.07) (xy 154.94 53.34)
		)
		(stroke
			(width 0)
			(type default)
		)
	)
	(wire
		(pts
			(xy 130.81 44.45) (xy 130.81 45.72)
		)
		(stroke
			(width 0)
			(type default)
		)
	)
	(wire
		(pts
			(xy 228.6 226.06) (xy 220.98 226.06)
		)
		(stroke
			(width 0)
			(type default)
		)
	)
	(wire
		(pts
			(xy 228.6 203.2) (xy 220.98 203.2)
		)
		(stroke
			(width 0)
			(type default)
		)
	)
	(wire
		(pts
			(xy 246.38 82.55) (xy 236.22 82.55)
		)
		(stroke
			(width 0)
			(type default)
		)
	)
	(wire
		(pts
			(xy 220.98 200.66) (xy 220.98 198.12)
		)
		(stroke
			(width 0)
			(type default)
		)
	)
	(wire
		(pts
			(xy 170.18 38.1) (xy 170.18 39.37)
		)
		(stroke
			(width 0)
			(type default)
		)
	)
	(wire
		(pts
			(xy 240.03 195.58) (xy 233.68 195.58)
		)
		(stroke
			(width 0)
			(type default)
		)
	)
	(wire
		(pts
			(xy 220.98 218.44) (xy 220.98 220.98)
		)
		(stroke
			(width 0)
			(type default)
		)
	)
	(wire
		(pts
			(xy 149.86 195.58) (xy 152.4 195.58)
		)
		(stroke
			(width 0)
			(type default)
		)
	)
	(wire
		(pts
			(xy 185.42 195.58) (xy 177.8 195.58)
		)
		(stroke
			(width 0)
			(type default)
		)
	)
	(wire
		(pts
			(xy 170.18 203.2) (xy 177.8 203.2)
		)
		(stroke
			(width 0)
			(type default)
		)
	)
	(wire
		(pts
			(xy 220.98 248.92) (xy 220.98 251.46)
		)
		(stroke
			(width 0)
			(type default)
		)
	)
	(wire
		(pts
			(xy 152.4 195.58) (xy 152.4 198.12)
		)
		(stroke
			(width 0)
			(type default)
		)
	)
	(wire
		(pts
			(xy 220.98 241.3) (xy 228.6 241.3)
		)
		(stroke
			(width 0)
			(type default)
		)
	)
	(wire
		(pts
			(xy 123.19 185.42) (xy 123.19 186.69)
		)
		(stroke
			(width 0)
			(type default)
		)
	)
	(wire
		(pts
			(xy 190.5 69.85) (xy 200.66 69.85)
		)
		(stroke
			(width 0)
			(type default)
		)
	)
	(wire
		(pts
			(xy 190.5 85.09) (xy 200.66 85.09)
		)
		(stroke
			(width 0)
			(type default)
		)
	)
	(wire
		(pts
			(xy 139.7 58.42) (xy 139.7 59.69)
		)
		(stroke
			(width 0)
			(type default)
		)
	)
	(wire
		(pts
			(xy 240.03 200.66) (xy 233.68 200.66)
		)
		(stroke
			(width 0)
			(type default)
		)
	)
	(wire
		(pts
			(xy 139.7 38.1) (xy 139.7 39.37)
		)
		(stroke
			(width 0)
			(type default)
		)
	)
	(wire
		(pts
			(xy 139.7 60.96) (xy 139.7 59.69)
		)
		(stroke
			(width 0)
			(type default)
		)
	)
	(wire
		(pts
			(xy 162.56 52.07) (xy 162.56 53.34)
		)
		(stroke
			(width 0)
			(type default)
		)
	)
	(wire
		(pts
			(xy 101.6 82.55) (xy 101.6 83.82)
		)
		(stroke
			(width 0)
			(type default)
		)
	)
	(wire
		(pts
			(xy 149.86 198.12) (xy 152.4 198.12)
		)
		(stroke
			(width 0)
			(type default)
		)
	)
	(wire
		(pts
			(xy 102.87 185.42) (xy 107.95 185.42)
		)
		(stroke
			(width 0)
			(type default)
		)
	)
	(wire
		(pts
			(xy 139.7 59.69) (xy 147.32 59.69)
		)
		(stroke
			(width 0)
			(type default)
		)
	)
	(wire
		(pts
			(xy 240.03 259.08) (xy 233.68 259.08)
		)
		(stroke
			(width 0)
			(type default)
		)
	)
	(wire
		(pts
			(xy 246.38 87.63) (xy 236.22 87.63)
		)
		(stroke
			(width 0)
			(type default)
		)
	)
	(wire
		(pts
			(xy 128.27 222.25) (xy 128.27 207.01)
		)
		(stroke
			(width 0)
			(type default)
		)
	)
	(wire
		(pts
			(xy 190.5 146.05) (xy 200.66 146.05)
		)
		(stroke
			(width 0)
			(type default)
		)
	)
	(wire
		(pts
			(xy 170.18 218.44) (xy 170.18 219.71)
		)
		(stroke
			(width 0)
			(type default)
		)
	)
	(wire
		(pts
			(xy 228.6 220.98) (xy 220.98 220.98)
		)
		(stroke
			(width 0)
			(type default)
		)
	)
	(wire
		(pts
			(xy 198.12 59.69) (xy 200.66 59.69)
		)
		(stroke
			(width 0)
			(type default)
		)
	)
	(wire
		(pts
			(xy 101.6 82.55) (xy 97.79 82.55)
		)
		(stroke
			(width 0)
			(type default)
		)
	)
	(wire
		(pts
			(xy 243.84 59.69) (xy 252.73 59.69)
		)
		(stroke
			(width 0)
			(type default)
		)
	)
	(wire
		(pts
			(xy 240.03 241.3) (xy 233.68 241.3)
		)
		(stroke
			(width 0)
			(type default)
		)
	)
	(wire
		(pts
			(xy 154.94 38.1) (xy 154.94 39.37)
		)
		(stroke
			(width 0)
			(type default)
		)
	)
	(wire
		(pts
			(xy 240.03 213.36) (xy 233.68 213.36)
		)
		(stroke
			(width 0)
			(type default)
		)
	)
	(wire
		(pts
			(xy 238.76 59.69) (xy 238.76 52.07)
		)
		(stroke
			(width 0)
			(type default)
		)
	)
	(wire
		(pts
			(xy 139.7 45.72) (xy 147.32 45.72)
		)
		(stroke
			(width 0)
			(type default)
		)
	)
	(wire
		(pts
			(xy 114.3 213.36) (xy 114.3 212.09)
		)
		(stroke
			(width 0)
			(type default)
		)
	)
	(wire
		(pts
			(xy 162.56 195.58) (xy 162.56 196.85)
		)
		(stroke
			(width 0)
			(type default)
		)
	)
	(wire
		(pts
			(xy 105.41 196.85) (xy 105.41 198.12)
		)
		(stroke
			(width 0)
			(type default)
		)
	)
	(wire
		(pts
			(xy 252.73 58.42) (xy 252.73 59.69)
		)
		(stroke
			(width 0)
			(type default)
		)
	)
	(wire
		(pts
			(xy 220.98 241.3) (xy 220.98 243.84)
		)
		(stroke
			(width 0)
			(type default)
		)
	)
	(wire
		(pts
			(xy 246.38 105.41) (xy 236.22 105.41)
		)
		(stroke
			(width 0)
			(type default)
		)
	)
	(wire
		(pts
			(xy 177.8 203.2) (xy 185.42 203.2)
		)
		(stroke
			(width 0)
			(type default)
		)
	)
	(wire
		(pts
			(xy 220.98 195.58) (xy 220.98 198.12)
		)
		(stroke
			(width 0)
			(type default)
		)
	)
	(wire
		(pts
			(xy 162.56 212.09) (xy 170.18 212.09)
		)
		(stroke
			(width 0)
			(type default)
		)
	)
	(wire
		(pts
			(xy 190.5 118.11) (xy 200.66 118.11)
		)
		(stroke
			(width 0)
			(type default)
		)
	)
	(wire
		(pts
			(xy 233.68 243.84) (xy 240.03 243.84)
		)
		(stroke
			(width 0)
			(type default)
		)
	)
	(wire
		(pts
			(xy 114.3 222.25) (xy 114.3 223.52)
		)
		(stroke
			(width 0)
			(type default)
		)
	)
	(wire
		(pts
			(xy 220.98 223.52) (xy 220.98 226.06)
		)
		(stroke
			(width 0)
			(type default)
		)
	)
	(wire
		(pts
			(xy 220.98 203.2) (xy 220.98 205.74)
		)
		(stroke
			(width 0)
			(type default)
		)
	)
	(wire
		(pts
			(xy 236.22 146.05) (xy 238.76 146.05)
		)
		(stroke
			(width 0)
			(type default)
		)
	)
	(wire
		(pts
			(xy 105.41 212.09) (xy 114.3 212.09)
		)
		(stroke
			(width 0)
			(type default)
		)
	)
	(wire
		(pts
			(xy 228.6 251.46) (xy 220.98 251.46)
		)
		(stroke
			(width 0)
			(type default)
		)
	)
	(wire
		(pts
			(xy 170.18 59.69) (xy 177.8 59.69)
		)
		(stroke
			(width 0)
			(type default)
		)
	)
	(wire
		(pts
			(xy 114.3 191.77) (xy 114.3 200.66)
		)
		(stroke
			(width 0)
			(type default)
		)
	)
	(wire
		(pts
			(xy 147.32 52.07) (xy 147.32 53.34)
		)
		(stroke
			(width 0)
			(type default)
		)
	)
	(wire
		(pts
			(xy 101.6 99.06) (xy 101.6 100.33)
		)
		(stroke
			(width 0)
			(type default)
		)
	)
	(wire
		(pts
			(xy 228.6 195.58) (xy 220.98 195.58)
		)
		(stroke
			(width 0)
			(type default)
		)
	)
	(wire
		(pts
			(xy 177.8 201.93) (xy 177.8 203.2)
		)
		(stroke
			(width 0)
			(type default)
		)
	)
	(wire
		(pts
			(xy 220.98 233.68) (xy 228.6 233.68)
		)
		(stroke
			(width 0)
			(type default)
		)
	)
	(wire
		(pts
			(xy 220.98 228.6) (xy 220.98 231.14)
		)
		(stroke
			(width 0)
			(type default)
		)
	)
	(wire
		(pts
			(xy 162.56 45.72) (xy 170.18 45.72)
		)
		(stroke
			(width 0)
			(type default)
		)
	)
	(wire
		(pts
			(xy 243.84 58.42) (xy 243.84 59.69)
		)
		(stroke
			(width 0)
			(type default)
		)
	)
	(wire
		(pts
			(xy 170.18 219.71) (xy 170.18 220.98)
		)
		(stroke
			(width 0)
			(type default)
		)
	)
	(wire
		(pts
			(xy 240.03 218.44) (xy 233.68 218.44)
		)
		(stroke
			(width 0)
			(type default)
		)
	)
	(wire
		(pts
			(xy 147.32 44.45) (xy 147.32 45.72)
		)
		(stroke
			(width 0)
			(type default)
		)
	)
	(wire
		(pts
			(xy 220.98 248.92) (xy 228.6 248.92)
		)
		(stroke
			(width 0)
			(type default)
		)
	)
	(wire
		(pts
			(xy 154.94 58.42) (xy 154.94 59.69)
		)
		(stroke
			(width 0)
			(type default)
		)
	)
	(wire
		(pts
			(xy 190.5 133.35) (xy 200.66 133.35)
		)
		(stroke
			(width 0)
			(type default)
		)
	)
	(wire
		(pts
			(xy 240.03 198.12) (xy 233.68 198.12)
		)
		(stroke
			(width 0)
			(type default)
		)
	)
	(wire
		(pts
			(xy 170.18 44.45) (xy 170.18 45.72)
		)
		(stroke
			(width 0)
			(type default)
		)
	)
	(wire
		(pts
			(xy 220.98 254) (xy 220.98 256.54)
		)
		(stroke
			(width 0)
			(type default)
		)
	)
	(wire
		(pts
			(xy 162.56 38.1) (xy 170.18 38.1)
		)
		(stroke
			(width 0)
			(type default)
		)
	)
	(wire
		(pts
			(xy 154.94 59.69) (xy 162.56 59.69)
		)
		(stroke
			(width 0)
			(type default)
		)
	)
	(wire
		(pts
			(xy 123.19 52.07) (xy 139.7 52.07)
		)
		(stroke
			(width 0)
			(type default)
		)
	)
	(wire
		(pts
			(xy 154.94 52.07) (xy 162.56 52.07)
		)
		(stroke
			(width 0)
			(type default)
		)
	)
	(wire
		(pts
			(xy 139.7 38.1) (xy 147.32 38.1)
		)
		(stroke
			(width 0)
			(type default)
		)
	)
	(wire
		(pts
			(xy 246.38 95.25) (xy 236.22 95.25)
		)
		(stroke
			(width 0)
			(type default)
		)
	)
	(wire
		(pts
			(xy 220.98 251.46) (xy 220.98 254)
		)
		(stroke
			(width 0)
			(type default)
		)
	)
	(wire
		(pts
			(xy 220.98 220.98) (xy 220.98 223.52)
		)
		(stroke
			(width 0)
			(type default)
		)
	)
	(wire
		(pts
			(xy 162.56 44.45) (xy 162.56 45.72)
		)
		(stroke
			(width 0)
			(type default)
		)
	)
	(wire
		(pts
			(xy 177.8 44.45) (xy 177.8 45.72)
		)
		(stroke
			(width 0)
			(type default)
		)
	)
	(wire
		(pts
			(xy 190.5 120.65) (xy 200.66 120.65)
		)
		(stroke
			(width 0)
			(type default)
		)
	)
	(wire
		(pts
			(xy 220.98 218.44) (xy 228.6 218.44)
		)
		(stroke
			(width 0)
			(type default)
		)
	)
	(wire
		(pts
			(xy 246.38 115.57) (xy 236.22 115.57)
		)
		(stroke
			(width 0)
			(type default)
		)
	)
	(wire
		(pts
			(xy 190.5 72.39) (xy 200.66 72.39)
		)
		(stroke
			(width 0)
			(type default)
		)
	)
	(wire
		(pts
			(xy 105.41 204.47) (xy 105.41 203.2)
		)
		(stroke
			(width 0)
			(type default)
		)
	)
	(wire
		(pts
			(xy 185.42 195.58) (xy 220.98 195.58)
		)
		(stroke
			(width 0)
			(type default)
		)
	)
	(wire
		(pts
			(xy 162.56 58.42) (xy 162.56 59.69)
		)
		(stroke
			(width 0)
			(type default)
		)
	)
	(wire
		(pts
			(xy 238.76 52.07) (xy 243.84 52.07)
		)
		(stroke
			(width 0)
			(type default)
		)
	)
	(wire
		(pts
			(xy 190.5 110.49) (xy 200.66 110.49)
		)
		(stroke
			(width 0)
			(type default)
		)
	)
	(wire
		(pts
			(xy 152.4 195.58) (xy 162.56 195.58)
		)
		(stroke
			(width 0)
			(type default)
		)
	)
	(wire
		(pts
			(xy 170.18 58.42) (xy 170.18 59.69)
		)
		(stroke
			(width 0)
			(type default)
		)
	)
	(wire
		(pts
			(xy 130.81 38.1) (xy 130.81 39.37)
		)
		(stroke
			(width 0)
			(type default)
		)
	)
	(wire
		(pts
			(xy 240.03 233.68) (xy 233.68 233.68)
		)
		(stroke
			(width 0)
			(type default)
		)
	)
	(wire
		(pts
			(xy 246.38 110.49) (xy 236.22 110.49)
		)
		(stroke
			(width 0)
			(type default)
		)
	)
	(wire
		(pts
			(xy 177.8 58.42) (xy 177.8 59.69)
		)
		(stroke
			(width 0)
			(type default)
		)
	)
	(wire
		(pts
			(xy 97.79 60.96) (xy 101.6 60.96)
		)
		(stroke
			(width 0)
			(type default)
		)
	)
	(wire
		(pts
			(xy 228.6 198.12) (xy 220.98 198.12)
		)
		(stroke
			(width 0)
			(type default)
		)
	)
	(wire
		(pts
			(xy 190.5 115.57) (xy 200.66 115.57)
		)
		(stroke
			(width 0)
			(type default)
		)
	)
	(wire
		(pts
			(xy 105.41 196.85) (xy 102.87 196.85)
		)
		(stroke
			(width 0)
			(type default)
		)
	)
	(wire
		(pts
			(xy 123.19 198.12) (xy 129.54 198.12)
		)
		(stroke
			(width 0)
			(type default)
		)
	)
	(wire
		(pts
			(xy 190.5 62.23) (xy 200.66 62.23)
		)
		(stroke
			(width 0)
			(type default)
		)
	)
	(wire
		(pts
			(xy 191.77 39.37) (xy 191.77 38.1)
		)
		(stroke
			(width 0)
			(type default)
		)
	)
	(wire
		(pts
			(xy 114.3 91.44) (xy 114.3 92.71)
		)
		(stroke
			(width 0)
			(type default)
		)
	)
	(wire
		(pts
			(xy 177.8 45.72) (xy 185.42 45.72)
		)
		(stroke
			(width 0)
			(type default)
		)
	)
	(wire
		(pts
			(xy 123.19 185.42) (xy 128.27 185.42)
		)
		(stroke
			(width 0)
			(type default)
		)
	)
	(wire
		(pts
			(xy 101.6 60.96) (xy 101.6 62.23)
		)
		(stroke
			(width 0)
			(type default)
		)
	)
	(wire
		(pts
			(xy 238.76 143.51) (xy 238.76 146.05)
		)
		(stroke
			(width 0)
			(type default)
		)
	)
	(wire
		(pts
			(xy 220.98 246.38) (xy 220.98 248.92)
		)
		(stroke
			(width 0)
			(type default)
		)
	)
	(wire
		(pts
			(xy 185.42 201.93) (xy 185.42 203.2)
		)
		(stroke
			(width 0)
			(type default)
		)
	)
	(wire
		(pts
			(xy 190.5 138.43) (xy 200.66 138.43)
		)
		(stroke
			(width 0)
			(type default)
		)
	)
	(wire
		(pts
			(xy 190.5 125.73) (xy 200.66 125.73)
		)
		(stroke
			(width 0)
			(type default)
		)
	)
	(wire
		(pts
			(xy 128.27 207.01) (xy 129.54 207.01)
		)
		(stroke
			(width 0)
			(type default)
		)
	)
	(wire
		(pts
			(xy 123.19 191.77) (xy 123.19 198.12)
		)
		(stroke
			(width 0)
			(type default)
		)
	)
	(wire
		(pts
			(xy 191.77 45.72) (xy 191.77 44.45)
		)
		(stroke
			(width 0)
			(type default)
		)
	)
	(wire
		(pts
			(xy 236.22 143.51) (xy 238.76 143.51)
		)
		(stroke
			(width 0)
			(type default)
		)
	)
	(wire
		(pts
			(xy 246.38 90.17) (xy 236.22 90.17)
		)
		(stroke
			(width 0)
			(type default)
		)
	)
	(wire
		(pts
			(xy 101.6 91.44) (xy 114.3 91.44)
		)
		(stroke
			(width 0)
			(type default)
		)
	)
	(wire
		(pts
			(xy 190.5 107.95) (xy 200.66 107.95)
		)
		(stroke
			(width 0)
			(type default)
		)
	)
	(wire
		(pts
			(xy 190.5 82.55) (xy 200.66 82.55)
		)
		(stroke
			(width 0)
			(type default)
		)
	)
	(wire
		(pts
			(xy 240.03 254) (xy 233.68 254)
		)
		(stroke
			(width 0)
			(type default)
		)
	)
	(wire
		(pts
			(xy 220.98 243.84) (xy 220.98 246.38)
		)
		(stroke
			(width 0)
			(type default)
		)
	)
	(label "DDR3_VTT"
		(at 203.2 195.58 0)
		(effects
			(font
				(size 1.27 1.27)
			)
			(justify left bottom)
		)
	)
	(global_label "DDR3_BA2"
		(shape input)
		(at 190.5 146.05 180)
		(fields_autoplaced yes)
		(effects
			(font
				(size 1.27 1.27)
			)
			(justify right)
		)
		(property "Intersheetrefs" "${INTERSHEET_REFS}"
			(at 97.79 33.655 0)
			(effects
				(font
					(size 1.27 1.27)
				)
				(hide yes)
			)
		)
	)
	(global_label "DDR3_DQ4"
		(shape bidirectional)
		(at 246.38 90.17 0)
		(fields_autoplaced yes)
		(effects
			(font
				(size 1.27 1.27)
			)
			(justify left)
		)
		(property "Intersheetrefs" "${INTERSHEET_REFS}"
			(at 82.55 13.335 0)
			(effects
				(font
					(size 1.27 1.27)
				)
				(hide yes)
			)
		)
	)
	(global_label "DDR3_A12"
		(shape input)
		(at 190.5 133.35 180)
		(fields_autoplaced yes)
		(effects
			(font
				(size 1.27 1.27)
			)
			(justify right)
		)
		(property "Intersheetrefs" "${INTERSHEET_REFS}"
			(at 97.79 36.195 0)
			(effects
				(font
					(size 1.27 1.27)
				)
				(hide yes)
			)
		)
	)
	(global_label "DDR3_DQS1_P"
		(shape bidirectional)
		(at 246.38 72.39 0)
		(fields_autoplaced yes)
		(effects
			(font
				(size 1.27 1.27)
			)
			(justify left)
		)
		(property "Intersheetrefs" "${INTERSHEET_REFS}"
			(at 82.55 -50.165 0)
			(effects
				(font
					(size 1.27 1.27)
				)
				(hide yes)
			)
		)
	)
	(global_label "DDR3_A8"
		(shape passive)
		(at 240.03 248.92 0)
		(fields_autoplaced yes)
		(effects
			(font
				(size 1.27 1.27)
			)
			(justify left)
		)
		(property "Intersheetrefs" "${INTERSHEET_REFS}"
			(at 352.425 -17.145 0)
			(effects
				(font
					(size 1.27 1.27)
				)
				(justify left)
				(hide yes)
			)
		)
	)
	(global_label "DDR3_BA1"
		(shape passive)
		(at 240.03 251.46 0)
		(fields_autoplaced yes)
		(effects
			(font
				(size 1.27 1.27)
			)
			(justify left)
		)
		(property "Intersheetrefs" "${INTERSHEET_REFS}"
			(at 352.425 -17.145 0)
			(effects
				(font
					(size 1.27 1.27)
				)
				(justify left)
				(hide yes)
			)
		)
	)
	(global_label "DDR3_A1"
		(shape passive)
		(at 240.03 233.68 0)
		(fields_autoplaced yes)
		(effects
			(font
				(size 1.27 1.27)
			)
			(justify left)
		)
		(property "Intersheetrefs" "${INTERSHEET_REFS}"
			(at 352.425 -4.445 0)
			(effects
				(font
					(size 1.27 1.27)
				)
				(justify left)
				(hide yes)
			)
		)
	)
	(global_label "DDR3_ODT"
		(shape input)
		(at 190.5 82.55 180)
		(fields_autoplaced yes)
		(effects
			(font
				(size 1.27 1.27)
			)
			(justify right)
		)
		(property "Intersheetrefs" "${INTERSHEET_REFS}"
			(at 97.79 -57.785 0)
			(effects
				(font
					(size 1.27 1.27)
				)
				(hide yes)
			)
		)
	)
	(global_label "DDR3_A5"
		(shape input)
		(at 190.5 115.57 180)
		(fields_autoplaced yes)
		(effects
			(font
				(size 1.27 1.27)
			)
			(justify right)
		)
		(property "Intersheetrefs" "${INTERSHEET_REFS}"
			(at 97.79 36.195 0)
			(effects
				(font
					(size 1.27 1.27)
				)
				(hide yes)
			)
		)
	)
	(global_label "DDR3_DQ6"
		(shape bidirectional)
		(at 246.38 95.25 0)
		(fields_autoplaced yes)
		(effects
			(font
				(size 1.27 1.27)
			)
			(justify left)
		)
		(property "Intersheetrefs" "${INTERSHEET_REFS}"
			(at 82.55 13.335 0)
			(effects
				(font
					(size 1.27 1.27)
				)
				(hide yes)
			)
		)
	)
	(global_label "DDR3_A7"
		(shape input)
		(at 190.5 120.65 180)
		(fields_autoplaced yes)
		(effects
			(font
				(size 1.27 1.27)
			)
			(justify right)
		)
		(property "Intersheetrefs" "${INTERSHEET_REFS}"
			(at 97.79 36.195 0)
			(effects
				(font
					(size 1.27 1.27)
				)
				(hide yes)
			)
		)
	)
	(global_label "DDR3_DQ13"
		(shape bidirectional)
		(at 246.38 113.03 0)
		(fields_autoplaced yes)
		(effects
			(font
				(size 1.27 1.27)
			)
			(justify left)
		)
		(property "Intersheetrefs" "${INTERSHEET_REFS}"
			(at 82.55 13.335 0)
			(effects
				(font
					(size 1.27 1.27)
				)
				(hide yes)
			)
		)
	)
	(global_label "DDR3_A11"
		(shape passive)
		(at 240.03 236.22 0)
		(fields_autoplaced yes)
		(effects
			(font
				(size 1.27 1.27)
			)
			(justify left)
		)
		(property "Intersheetrefs" "${INTERSHEET_REFS}"
			(at 352.425 -4.445 0)
			(effects
				(font
					(size 1.27 1.27)
				)
				(justify left)
				(hide yes)
			)
		)
	)
	(global_label "VCC1V35"
		(shape input)
		(at 102.87 196.85 180)
		(fields_autoplaced yes)
		(effects
			(font
				(size 1.27 1.27)
			)
			(justify right)
		)
		(property "Intersheetrefs" "${INTERSHEET_REFS}"
			(at -52.07 -6.35 0)
			(effects
				(font
					(size 1.27 1.27)
				)
				(justify right)
				(hide yes)
			)
		)
	)
	(global_label "VCC1V35"
		(shape input)
		(at 102.87 222.25 180)
		(fields_autoplaced yes)
		(effects
			(font
				(size 1.27 1.27)
			)
			(justify right)
		)
		(property "Intersheetrefs" "${INTERSHEET_REFS}"
			(at 328.295 43.815 0)
			(effects
				(font
					(size 1.27 1.27)
				)
				(justify left)
				(hide yes)
			)
		)
	)
	(global_label "DDR3_CLK_N"
		(shape input)
		(at 190.5 97.79 180)
		(fields_autoplaced yes)
		(effects
			(font
				(size 1.27 1.27)
			)
			(justify right)
		)
		(property "Intersheetrefs" "${INTERSHEET_REFS}"
			(at 97.79 -22.225 0)
			(effects
				(font
					(size 1.27 1.27)
				)
				(hide yes)
			)
		)
	)
	(global_label "DDR3_WE"
		(shape input)
		(at 190.5 74.93 180)
		(fields_autoplaced yes)
		(effects
			(font
				(size 1.27 1.27)
			)
			(justify right)
		)
		(property "Intersheetrefs" "${INTERSHEET_REFS}"
			(at 97.79 -62.865 0)
			(effects
				(font
					(size 1.27 1.27)
				)
				(hide yes)
			)
		)
	)
	(global_label "DDR3_DM0"
		(shape bidirectional)
		(at 190.5 85.09 180)
		(fields_autoplaced yes)
		(effects
			(font
				(size 1.27 1.27)
			)
			(justify right)
		)
		(property "Intersheetrefs" "${INTERSHEET_REFS}"
			(at 354.33 -24.765 0)
			(effects
				(font
					(size 1.27 1.27)
				)
				(justify left)
				(hide yes)
			)
		)
	)
	(global_label "DDR3_BA2"
		(shape passive)
		(at 240.03 208.28 0)
		(fields_autoplaced yes)
		(effects
			(font
				(size 1.27 1.27)
			)
			(justify left)
		)
		(property "Intersheetrefs" "${INTERSHEET_REFS}"
			(at 352.425 8.255 0)
			(effects
				(font
					(size 1.27 1.27)
				)
				(justify left)
				(hide yes)
			)
		)
	)
	(global_label "DDR3_DQ8"
		(shape bidirectional)
		(at 246.38 100.33 0)
		(fields_autoplaced yes)
		(effects
			(font
				(size 1.27 1.27)
			)
			(justify left)
		)
		(property "Intersheetrefs" "${INTERSHEET_REFS}"
			(at 82.55 13.335 0)
			(effects
				(font
					(size 1.27 1.27)
				)
				(hide yes)
			)
		)
	)
	(global_label "DDR3_DQ15"
		(shape bidirectional)
		(at 246.38 118.11 0)
		(fields_autoplaced yes)
		(effects
			(font
				(size 1.27 1.27)
			)
			(justify left)
		)
		(property "Intersheetrefs" "${INTERSHEET_REFS}"
			(at 82.55 13.335 0)
			(effects
				(font
					(size 1.27 1.27)
				)
				(hide yes)
			)
		)
	)
	(global_label "VCC3V3"
		(shape tri_state)
		(at 102.87 185.42 180)
		(fields_autoplaced yes)
		(effects
			(font
				(size 1.27 1.27)
			)
			(justify right)
		)
		(property "Intersheetrefs" "${INTERSHEET_REFS}"
			(at 339.725 -22.86 0)
			(effects
				(font
					(size 1.27 1.27)
				)
				(justify left)
				(hide yes)
			)
		)
	)
	(global_label "DDR3_A14"
		(shape input)
		(at 190.5 138.43 180)
		(fields_autoplaced yes)
		(effects
			(font
				(size 1.27 1.27)
			)
			(justify right)
		)
		(property "Intersheetrefs" "${INTERSHEET_REFS}"
			(at 97.79 36.195 0)
			(effects
				(font
					(size 1.27 1.27)
				)
				(hide yes)
			)
		)
	)
	(global_label "DDR3_CS"
		(shape passive)
		(at 240.03 259.08 0)
		(fields_autoplaced yes)
		(effects
			(font
				(size 1.27 1.27)
			)
			(justify left)
		)
		(property "Intersheetrefs" "${INTERSHEET_REFS}"
			(at 352.425 -17.145 0)
			(effects
				(font
					(size 1.27 1.27)
				)
				(justify left)
				(hide yes)
			)
		)
	)
	(global_label "DDR3_A4"
		(shape passive)
		(at 240.03 243.84 0)
		(fields_autoplaced yes)
		(effects
			(font
				(size 1.27 1.27)
			)
			(justify left)
		)
		(property "Intersheetrefs" "${INTERSHEET_REFS}"
			(at 352.425 -17.145 0)
			(effects
				(font
					(size 1.27 1.27)
				)
				(justify left)
				(hide yes)
			)
		)
	)
	(global_label "DDR3_DQ12"
		(shape bidirectional)
		(at 246.38 110.49 0)
		(fields_autoplaced yes)
		(effects
			(font
				(size 1.27 1.27)
			)
			(justify left)
		)
		(property "Intersheetrefs" "${INTERSHEET_REFS}"
			(at 82.55 13.335 0)
			(effects
				(font
					(size 1.27 1.27)
				)
				(hide yes)
			)
		)
	)
	(global_label "DDR3_DQS0_P"
		(shape bidirectional)
		(at 246.38 67.31 0)
		(fields_autoplaced yes)
		(effects
			(font
				(size 1.27 1.27)
			)
			(justify left)
		)
		(property "Intersheetrefs" "${INTERSHEET_REFS}"
			(at 82.55 -50.165 0)
			(effects
				(font
					(size 1.27 1.27)
				)
				(hide yes)
			)
		)
	)
	(global_label "DDR3_RESET"
		(shape input)
		(at 190.5 67.31 180)
		(fields_autoplaced yes)
		(effects
			(font
				(size 1.27 1.27)
			)
			(justify right)
		)
		(property "Intersheetrefs" "${INTERSHEET_REFS}"
			(at 97.79 -60.325 0)
			(effects
				(font
					(size 1.27 1.27)
				)
				(hide yes)
			)
		)
	)
	(global_label "DDR3_RESET"
		(shape input)
		(at 97.79 60.96 180)
		(fields_autoplaced yes)
		(effects
			(font
				(size 1.27 1.27)
			)
			(justify right)
		)
		(property "Intersheetrefs" "${INTERSHEET_REFS}"
			(at 6.35 -90.17 0)
			(effects
				(font
					(size 1.27 1.27)
				)
				(hide yes)
			)
		)
	)
	(global_label "DDR3_CKE"
		(shape input)
		(at 190.5 92.71 180)
		(fields_autoplaced yes)
		(effects
			(font
				(size 1.27 1.27)
			)
			(justify right)
		)
		(property "Intersheetrefs" "${INTERSHEET_REFS}"
			(at 97.79 -29.845 0)
			(effects
				(font
					(size 1.27 1.27)
				)
				(hide yes)
			)
		)
	)
	(global_label "DDR3_CKE"
		(shape passive)
		(at 240.03 254 0)
		(fields_autoplaced yes)
		(effects
			(font
				(size 1.27 1.27)
			)
			(justify left)
		)
		(property "Intersheetrefs" "${INTERSHEET_REFS}"
			(at 352.425 -17.145 0)
			(effects
				(font
					(size 1.27 1.27)
				)
				(justify left)
				(hide yes)
			)
		)
	)
	(global_label "DDR3_CAS"
		(shape input)
		(at 190.5 72.39 180)
		(fields_autoplaced yes)
		(effects
			(font
				(size 1.27 1.27)
			)
			(justify right)
		)
		(property "Intersheetrefs" "${INTERSHEET_REFS}"
			(at 97.79 -62.865 0)
			(effects
				(font
					(size 1.27 1.27)
				)
				(hide yes)
			)
		)
	)
	(global_label "DDR3_BA0"
		(shape passive)
		(at 240.03 205.74 0)
		(fields_autoplaced yes)
		(effects
			(font
				(size 1.27 1.27)
			)
			(justify left)
		)
		(property "Intersheetrefs" "${INTERSHEET_REFS}"
			(at 352.425 8.255 0)
			(effects
				(font
					(size 1.27 1.27)
				)
				(justify left)
				(hide yes)
			)
		)
	)
	(global_label "DDR3_A0"
		(shape passive)
		(at 240.03 213.36 0)
		(fields_autoplaced yes)
		(effects
			(font
				(size 1.27 1.27)
			)
			(justify left)
		)
		(property "Intersheetrefs" "${INTERSHEET_REFS}"
			(at 352.425 8.255 0)
			(effects
				(font
					(size 1.27 1.27)
				)
				(justify left)
				(hide yes)
			)
		)
	)
	(global_label "DDR3_CLK_P"
		(shape input)
		(at 97.79 82.55 180)
		(fields_autoplaced yes)
		(effects
			(font
				(size 1.27 1.27)
			)
			(justify right)
		)
		(property "Intersheetrefs" "${INTERSHEET_REFS}"
			(at -215.265 -118.11 0)
			(effects
				(font
					(size 1.27 1.27)
				)
				(hide yes)
			)
		)
	)
	(global_label "DDR3_RAS"
		(shape passive)
		(at 240.03 195.58 0)
		(fields_autoplaced yes)
		(effects
			(font
				(size 1.27 1.27)
			)
			(justify left)
		)
		(property "Intersheetrefs" "${INTERSHEET_REFS}"
			(at 352.425 8.255 0)
			(effects
				(font
					(size 1.27 1.27)
				)
				(justify left)
				(hide yes)
			)
		)
	)
	(global_label "DDR3_A10"
		(shape input)
		(at 190.5 128.27 180)
		(fields_autoplaced yes)
		(effects
			(font
				(size 1.27 1.27)
			)
			(justify right)
		)
		(property "Intersheetrefs" "${INTERSHEET_REFS}"
			(at 97.79 36.195 0)
			(effects
				(font
					(size 1.27 1.27)
				)
				(hide yes)
			)
		)
	)
	(global_label "DDR3_DQ5"
		(shape bidirectional)
		(at 246.38 92.71 0)
		(fields_autoplaced yes)
		(effects
			(font
				(size 1.27 1.27)
			)
			(justify left)
		)
		(property "Intersheetrefs" "${INTERSHEET_REFS}"
			(at 82.55 13.335 0)
			(effects
				(font
					(size 1.27 1.27)
				)
				(hide yes)
			)
		)
	)
	(global_label "DDR3_CAS"
		(shape passive)
		(at 240.03 198.12 0)
		(fields_autoplaced yes)
		(effects
			(font
				(size 1.27 1.27)
			)
			(justify left)
		)
		(property "Intersheetrefs" "${INTERSHEET_REFS}"
			(at 352.425 8.255 0)
			(effects
				(font
					(size 1.27 1.27)
				)
				(justify left)
				(hide yes)
			)
		)
	)
	(global_label "DDR3_VREF"
		(shape input)
		(at 256.54 52.07 0)
		(fields_autoplaced yes)
		(effects
			(font
				(size 1.27 1.27)
			)
			(justify left)
		)
		(property "Intersheetrefs" "${INTERSHEET_REFS}"
			(at 531.495 -69.85 0)
			(effects
				(font
					(size 1.27 1.27)
				)
				(justify left)
				(hide yes)
			)
		)
	)
	(global_label "DDR3_VREF"
		(shape output)
		(at 177.8 212.09 0)
		(fields_autoplaced yes)
		(effects
			(font
				(size 1.27 1.27)
			)
			(justify left)
		)
		(property "Intersheetrefs" "${INTERSHEET_REFS}"
			(at 355.6 -15.24 0)
			(effects
				(font
					(size 1.27 1.27)
				)
				(justify left)
				(hide yes)
			)
		)
	)
	(global_label "DDR3_DM1"
		(shape bidirectional)
		(at 190.5 87.63 180)
		(fields_autoplaced yes)
		(effects
			(font
				(size 1.27 1.27)
			)
			(justify right)
		)
		(property "Intersheetrefs" "${INTERSHEET_REFS}"
			(at 354.33 -24.765 0)
			(effects
				(font
					(size 1.27 1.27)
				)
				(justify left)
				(hide yes)
			)
		)
	)
	(global_label "DDR3_BA0"
		(shape input)
		(at 190.5 140.97 180)
		(fields_autoplaced yes)
		(effects
			(font
				(size 1.27 1.27)
			)
			(justify right)
		)
		(property "Intersheetrefs" "${INTERSHEET_REFS}"
			(at 97.79 33.655 0)
			(effects
				(font
					(size 1.27 1.27)
				)
				(hide yes)
			)
		)
	)
	(global_label "DDR3_A9"
		(shape input)
		(at 190.5 125.73 180)
		(fields_autoplaced yes)
		(effects
			(font
				(size 1.27 1.27)
			)
			(justify right)
		)
		(property "Intersheetrefs" "${INTERSHEET_REFS}"
			(at 97.79 36.195 0)
			(effects
				(font
					(size 1.27 1.27)
				)
				(hide yes)
			)
		)
	)
	(global_label "DDR3_A8"
		(shape input)
		(at 190.5 123.19 180)
		(fields_autoplaced yes)
		(effects
			(font
				(size 1.27 1.27)
			)
			(justify right)
		)
		(property "Intersheetrefs" "${INTERSHEET_REFS}"
			(at 97.79 36.195 0)
			(effects
				(font
					(size 1.27 1.27)
				)
				(hide yes)
			)
		)
	)
	(global_label "DDR3_RAS"
		(shape input)
		(at 190.5 69.85 180)
		(fields_autoplaced yes)
		(effects
			(font
				(size 1.27 1.27)
			)
			(justify right)
		)
		(property "Intersheetrefs" "${INTERSHEET_REFS}"
			(at 97.79 -62.865 0)
			(effects
				(font
					(size 1.27 1.27)
				)
				(hide yes)
			)
		)
	)
	(global_label "DDR3_BA1"
		(shape input)
		(at 190.5 143.51 180)
		(fields_autoplaced yes)
		(effects
			(font
				(size 1.27 1.27)
			)
			(justify right)
		)
		(property "Intersheetrefs" "${INTERSHEET_REFS}"
			(at 97.79 33.655 0)
			(effects
				(font
					(size 1.27 1.27)
				)
				(hide yes)
			)
		)
	)
	(global_label "DDR3_DQ10"
		(shape bidirectional)
		(at 246.38 105.41 0)
		(fields_autoplaced yes)
		(effects
			(font
				(size 1.27 1.27)
			)
			(justify left)
		)
		(property "Intersheetrefs" "${INTERSHEET_REFS}"
			(at 82.55 13.335 0)
			(effects
				(font
					(size 1.27 1.27)
				)
				(hide yes)
			)
		)
	)
	(global_label "DDR3_WE"
		(shape passive)
		(at 240.03 203.2 0)
		(fields_autoplaced yes)
		(effects
			(font
				(size 1.27 1.27)
			)
			(justify left)
		)
		(property "Intersheetrefs" "${INTERSHEET_REFS}"
			(at 352.425 8.255 0)
			(effects
				(font
					(size 1.27 1.27)
				)
				(justify left)
				(hide yes)
			)
		)
	)
	(global_label "DDR3_A6"
		(shape passive)
		(at 240.03 246.38 0)
		(fields_autoplaced yes)
		(effects
			(font
				(size 1.27 1.27)
			)
			(justify left)
		)
		(property "Intersheetrefs" "${INTERSHEET_REFS}"
			(at 352.425 -17.145 0)
			(effects
				(font
					(size 1.27 1.27)
				)
				(justify left)
				(hide yes)
			)
		)
	)
	(global_label "DDR3_A12"
		(shape passive)
		(at 240.03 231.14 0)
		(fields_autoplaced yes)
		(effects
			(font
				(size 1.27 1.27)
			)
			(justify left)
		)
		(property "Intersheetrefs" "${INTERSHEET_REFS}"
			(at 352.425 -4.445 0)
			(effects
				(font
					(size 1.27 1.27)
				)
				(justify left)
				(hide yes)
			)
		)
	)
	(global_label "DDR3_A3"
		(shape passive)
		(at 240.03 210.82 0)
		(fields_autoplaced yes)
		(effects
			(font
				(size 1.27 1.27)
			)
			(justify left)
		)
		(property "Intersheetrefs" "${INTERSHEET_REFS}"
			(at 352.425 8.255 0)
			(effects
				(font
					(size 1.27 1.27)
				)
				(justify left)
				(hide yes)
			)
		)
	)
	(global_label "DDR3_DQ3"
		(shape bidirectional)
		(at 246.38 87.63 0)
		(fields_autoplaced yes)
		(effects
			(font
				(size 1.27 1.27)
			)
			(justify left)
		)
		(property "Intersheetrefs" "${INTERSHEET_REFS}"
			(at 82.55 13.335 0)
			(effects
				(font
					(size 1.27 1.27)
				)
				(hide yes)
			)
		)
	)
	(global_label "DDR3_DQ14"
		(shape bidirectional)
		(at 246.38 115.57 0)
		(fields_autoplaced yes)
		(effects
			(font
				(size 1.27 1.27)
			)
			(justify left)
		)
		(property "Intersheetrefs" "${INTERSHEET_REFS}"
			(at 82.55 13.335 0)
			(effects
				(font
					(size 1.27 1.27)
				)
				(hide yes)
			)
		)
	)
	(global_label "DDR3_DQ1"
		(shape bidirectional)
		(at 246.38 82.55 0)
		(fields_autoplaced yes)
		(effects
			(font
				(size 1.27 1.27)
			)
			(justify left)
		)
		(property "Intersheetrefs" "${INTERSHEET_REFS}"
			(at 82.55 13.335 0)
			(effects
				(font
					(size 1.27 1.27)
				)
				(hide yes)
			)
		)
	)
	(global_label "DDR3_DQ7"
		(shape bidirectional)
		(at 246.38 97.79 0)
		(fields_autoplaced yes)
		(effects
			(font
				(size 1.27 1.27)
			)
			(justify left)
		)
		(property "Intersheetrefs" "${INTERSHEET_REFS}"
			(at 82.55 13.335 0)
			(effects
				(font
					(size 1.27 1.27)
				)
				(hide yes)
			)
		)
	)
	(global_label "DDR3_ODT"
		(shape passive)
		(at 240.03 200.66 0)
		(fields_autoplaced yes)
		(effects
			(font
				(size 1.27 1.27)
			)
			(justify left)
		)
		(property "Intersheetrefs" "${INTERSHEET_REFS}"
			(at 352.425 8.255 0)
			(effects
				(font
					(size 1.27 1.27)
				)
				(justify left)
				(hide yes)
			)
		)
	)
	(global_label "DDR3_A2"
		(shape input)
		(at 190.5 107.95 180)
		(fields_autoplaced yes)
		(effects
			(font
				(size 1.27 1.27)
			)
			(justify right)
		)
		(property "Intersheetrefs" "${INTERSHEET_REFS}"
			(at 97.79 36.195 0)
			(effects
				(font
					(size 1.27 1.27)
				)
				(hide yes)
			)
		)
	)
	(global_label "DDR3_A11"
		(shape input)
		(at 190.5 130.81 180)
		(fields_autoplaced yes)
		(effects
			(font
				(size 1.27 1.27)
			)
			(justify right)
		)
		(property "Intersheetrefs" "${INTERSHEET_REFS}"
			(at 97.79 36.195 0)
			(effects
				(font
					(size 1.27 1.27)
				)
				(hide yes)
			)
		)
	)
	(global_label "DDR3_DQ2"
		(shape bidirectional)
		(at 246.38 85.09 0)
		(fields_autoplaced yes)
		(effects
			(font
				(size 1.27 1.27)
			)
			(justify left)
		)
		(property "Intersheetrefs" "${INTERSHEET_REFS}"
			(at 82.55 13.335 0)
			(effects
				(font
					(size 1.27 1.27)
				)
				(hide yes)
			)
		)
	)
	(global_label "DDR3_CS"
		(shape input)
		(at 190.5 77.47 180)
		(fields_autoplaced yes)
		(effects
			(font
				(size 1.27 1.27)
			)
			(justify right)
		)
		(property "Intersheetrefs" "${INTERSHEET_REFS}"
			(at 97.79 -52.705 0)
			(effects
				(font
					(size 1.27 1.27)
				)
				(hide yes)
			)
		)
	)
	(global_label "DDR3_DQ9"
		(shape bidirectional)
		(at 246.38 102.87 0)
		(fields_autoplaced yes)
		(effects
			(font
				(size 1.27 1.27)
			)
			(justify left)
		)
		(property "Intersheetrefs" "${INTERSHEET_REFS}"
			(at 82.55 13.335 0)
			(effects
				(font
					(size 1.27 1.27)
				)
				(hide yes)
			)
		)
	)
	(global_label "DDR3_A7"
		(shape passive)
		(at 240.03 220.98 0)
		(fields_autoplaced yes)
		(effects
			(font
				(size 1.27 1.27)
			)
			(justify left)
		)
		(property "Intersheetrefs" "${INTERSHEET_REFS}"
			(at 352.425 -4.445 0)
			(effects
				(font
					(size 1.27 1.27)
				)
				(justify left)
				(hide yes)
			)
		)
	)
	(global_label "DDR3_A6"
		(shape input)
		(at 190.5 118.11 180)
		(fields_autoplaced yes)
		(effects
			(font
				(size 1.27 1.27)
			)
			(justify right)
		)
		(property "Intersheetrefs" "${INTERSHEET_REFS}"
			(at 97.79 36.195 0)
			(effects
				(font
					(size 1.27 1.27)
				)
				(hide yes)
			)
		)
	)
	(global_label "DDR3_DQS1_N"
		(shape bidirectional)
		(at 246.38 74.93 0)
		(fields_autoplaced yes)
		(effects
			(font
				(size 1.27 1.27)
			)
			(justify left)
		)
		(property "Intersheetrefs" "${INTERSHEET_REFS}"
			(at 82.55 -50.165 0)
			(effects
				(font
					(size 1.27 1.27)
				)
				(hide yes)
			)
		)
	)
	(global_label "DDR3_A13"
		(shape passive)
		(at 240.03 228.6 0)
		(fields_autoplaced yes)
		(effects
			(font
				(size 1.27 1.27)
			)
			(justify left)
		)
		(property "Intersheetrefs" "${INTERSHEET_REFS}"
			(at 352.425 -4.445 0)
			(effects
				(font
					(size 1.27 1.27)
				)
				(justify left)
				(hide yes)
			)
		)
	)
	(global_label "DDR3_A2"
		(shape passive)
		(at 240.03 218.44 0)
		(fields_autoplaced yes)
		(effects
			(font
				(size 1.27 1.27)
			)
			(justify left)
		)
		(property "Intersheetrefs" "${INTERSHEET_REFS}"
			(at 352.425 -4.445 0)
			(effects
				(font
					(size 1.27 1.27)
				)
				(justify left)
				(hide yes)
			)
		)
	)
	(global_label "DDR3_CLK_N"
		(shape input)
		(at 97.79 100.33 180)
		(fields_autoplaced yes)
		(effects
			(font
				(size 1.27 1.27)
			)
			(justify right)
		)
		(property "Intersheetrefs" "${INTERSHEET_REFS}"
			(at -215.265 -118.11 0)
			(effects
				(font
					(size 1.27 1.27)
				)
				(hide yes)
			)
		)
	)
	(global_label "DDR3_A13"
		(shape input)
		(at 190.5 135.89 180)
		(fields_autoplaced yes)
		(effects
			(font
				(size 1.27 1.27)
			)
			(justify right)
		)
		(property "Intersheetrefs" "${INTERSHEET_REFS}"
			(at 97.79 36.195 0)
			(effects
				(font
					(size 1.27 1.27)
				)
				(hide yes)
			)
		)
	)
	(global_label "DDR3_A3"
		(shape input)
		(at 190.5 110.49 180)
		(fields_autoplaced yes)
		(effects
			(font
				(size 1.27 1.27)
			)
			(justify right)
		)
		(property "Intersheetrefs" "${INTERSHEET_REFS}"
			(at 97.79 36.195 0)
			(effects
				(font
					(size 1.27 1.27)
				)
				(hide yes)
			)
		)
	)
	(global_label "DDR3_A10"
		(shape passive)
		(at 240.03 256.54 0)
		(fields_autoplaced yes)
		(effects
			(font
				(size 1.27 1.27)
			)
			(justify left)
		)
		(property "Intersheetrefs" "${INTERSHEET_REFS}"
			(at 352.425 -17.145 0)
			(effects
				(font
					(size 1.27 1.27)
				)
				(justify left)
				(hide yes)
			)
		)
	)
	(global_label "DDR3_A0"
		(shape input)
		(at 190.5 102.87 180)
		(fields_autoplaced yes)
		(effects
			(font
				(size 1.27 1.27)
			)
			(justify right)
		)
		(property "Intersheetrefs" "${INTERSHEET_REFS}"
			(at 97.79 36.195 0)
			(effects
				(font
					(size 1.27 1.27)
				)
				(hide yes)
			)
		)
	)
	(global_label "DDR3_DQ0"
		(shape bidirectional)
		(at 246.38 80.01 0)
		(fields_autoplaced yes)
		(effects
			(font
				(size 1.27 1.27)
			)
			(justify left)
		)
		(property "Intersheetrefs" "${INTERSHEET_REFS}"
			(at 82.55 13.335 0)
			(effects
				(font
					(size 1.27 1.27)
				)
				(hide yes)
			)
		)
	)
	(global_label "VCC1V35"
		(shape input)
		(at 120.65 38.1 180)
		(fields_autoplaced yes)
		(effects
			(font
				(size 1.27 1.27)
			)
			(justify right)
		)
		(property "Intersheetrefs" "${INTERSHEET_REFS}"
			(at -176.53 -22.225 0)
			(effects
				(font
					(size 1.27 1.27)
				)
				(hide yes)
			)
		)
	)
	(global_label "DDR3_A14"
		(shape passive)
		(at 240.03 241.3 0)
		(fields_autoplaced yes)
		(effects
			(font
				(size 1.27 1.27)
			)
			(justify left)
		)
		(property "Intersheetrefs" "${INTERSHEET_REFS}"
			(at 352.425 -17.145 0)
			(effects
				(font
					(size 1.27 1.27)
				)
				(justify left)
				(hide yes)
			)
		)
	)
	(global_label "DDR3_CLK_P"
		(shape input)
		(at 190.5 95.25 180)
		(fields_autoplaced yes)
		(effects
			(font
				(size 1.27 1.27)
			)
			(justify right)
		)
		(property "Intersheetrefs" "${INTERSHEET_REFS}"
			(at 97.79 -22.225 0)
			(effects
				(font
					(size 1.27 1.27)
				)
				(hide yes)
			)
		)
	)
	(global_label "DDR3_A4"
		(shape input)
		(at 190.5 113.03 180)
		(fields_autoplaced yes)
		(effects
			(font
				(size 1.27 1.27)
			)
			(justify right)
		)
		(property "Intersheetrefs" "${INTERSHEET_REFS}"
			(at 97.79 36.195 0)
			(effects
				(font
					(size 1.27 1.27)
				)
				(hide yes)
			)
		)
	)
	(global_label "DDR3_DQS0_N"
		(shape bidirectional)
		(at 246.38 69.85 0)
		(fields_autoplaced yes)
		(effects
			(font
				(size 1.27 1.27)
			)
			(justify left)
		)
		(property "Intersheetrefs" "${INTERSHEET_REFS}"
			(at 82.55 -50.165 0)
			(effects
				(font
					(size 1.27 1.27)
				)
				(hide yes)
			)
		)
	)
	(global_label "DDR3_A5"
		(shape passive)
		(at 240.03 226.06 0)
		(fields_autoplaced yes)
		(effects
			(font
				(size 1.27 1.27)
			)
			(justify left)
		)
		(property "Intersheetrefs" "${INTERSHEET_REFS}"
			(at 352.425 -4.445 0)
			(effects
				(font
					(size 1.27 1.27)
				)
				(justify left)
				(hide yes)
			)
		)
	)
	(global_label "DDR3_A9"
		(shape passive)
		(at 240.03 223.52 0)
		(fields_autoplaced yes)
		(effects
			(font
				(size 1.27 1.27)
			)
			(justify left)
		)
		(property "Intersheetrefs" "${INTERSHEET_REFS}"
			(at 352.425 -4.445 0)
			(effects
				(font
					(size 1.27 1.27)
				)
				(justify left)
				(hide yes)
			)
		)
	)
	(global_label "DDR3_DQ11"
		(shape bidirectional)
		(at 246.38 107.95 0)
		(fields_autoplaced yes)
		(effects
			(font
				(size 1.27 1.27)
			)
			(justify left)
		)
		(property "Intersheetrefs" "${INTERSHEET_REFS}"
			(at 82.55 13.335 0)
			(effects
				(font
					(size 1.27 1.27)
				)
				(hide yes)
			)
		)
	)
	(global_label "DDR3_A1"
		(shape input)
		(at 190.5 105.41 180)
		(fields_autoplaced yes)
		(effects
			(font
				(size 1.27 1.27)
			)
			(justify right)
		)
		(property "Intersheetrefs" "${INTERSHEET_REFS}"
			(at 97.79 36.195 0)
			(effects
				(font
					(size 1.27 1.27)
				)
				(hide yes)
			)
		)
	)
	(symbol
		(lib_id "antmicroResistors0402:R_51R_0402")
		(at 101.6 88.9 270)
		(mirror x)
		(unit 1)
		(exclude_from_sim no)
		(in_bom no)
		(on_board yes)
		(dnp yes)
		(property "Reference" "R99"
			(at 102.87 85.09 90)
			(effects
				(font
					(size 1.27 1.27)
				)
				(justify left)
			)
		)
		(property "Value" "R_51R_0402"
			(at 88.9 68.58 0)
			(effects
				(font
					(size 1.27 1.27)
					(thickness 0.15)
				)
				(justify left bottom)
				(hide yes)
			)
		)
		(property "Footprint" "antmicro-footprints:R_0402_1005Metric"
			(at 86.36 68.58 0)
			(effects
				(font
					(size 1.27 1.27)
					(thickness 0.15)
				)
				(justify left bottom)
				(hide yes)
			)
		)
		(property "Datasheet" "https://www.bourns.com/docs/product-datasheets/cr.pdf"
			(at 83.82 68.58 0)
			(effects
				(font
					(size 1.27 1.27)
					(thickness 0.15)
				)
				(justify left bottom)
				(hide yes)
			)
		)
		(property "Description" "SMD Chip Resistor, 51 ohm, ± 1%, 63 mW, 0402 [1005 Metric], Thick Film, General Purpose"
			(at 101.6 88.9 0)
			(effects
				(font
					(size 1.27 1.27)
				)
				(hide yes)
			)
		)
		(property "Manufacturer" "Bourns"
			(at 78.74 68.58 0)
			(effects
				(font
					(size 1.27 1.27)
					(thickness 0.15)
				)
				(justify left bottom)
				(hide yes)
			)
		)
		(property "MPN" "CR0402-FX-51R0GLF"
			(at 81.28 68.58 0)
			(effects
				(font
					(size 1.27 1.27)
					(thickness 0.15)
				)
				(justify left bottom)
				(hide yes)
			)
		)
		(property "Val" "51R"
			(at 102.87 87.63 90)
			(effects
				(font
					(size 1.27 1.27)
					(thickness 0.15)
				)
				(justify left)
			)
		)
		(property "License" "Apache-2.0"
			(at 76.2 68.58 0)
			(effects
				(font
					(size 1.27 1.27)
					(thickness 0.15)
				)
				(justify left bottom)
				(hide yes)
			)
		)
		(property "Author" "Antmicro"
			(at 73.66 68.58 0)
			(effects
				(font
					(size 1.27 1.27)
					(thickness 0.15)
				)
				(justify left bottom)
				(hide yes)
			)
		)
		(property "Tolerance" "1%"
			(at 91.44 68.58 0)
			(effects
				(font
					(size 1.27 1.27)
				)
				(justify left bottom)
				(hide yes)
			)
		)
		(pin "1"
		)
		(pin "2"
		)
		(instances
			(project "artix-dc-scm"
				(path ""
					(reference "R99")
					(unit 1)
				)
			)
		)
	)
	(symbol
		(lib_id "antmicroResistors0402:R_51R_0402")
		(at 101.6 93.98 270)
		(unit 1)
		(exclude_from_sim no)
		(in_bom no)
		(on_board yes)
		(dnp yes)
		(property "Reference" "R100"
			(at 103.505 95.2499 90)
			(effects
				(font
					(size 1.27 1.27)
				)
				(justify left)
			)
		)
		(property "Value" "R_51R_0402"
			(at 88.9 114.3 0)
			(effects
				(font
					(size 1.27 1.27)
					(thickness 0.15)
				)
				(justify left bottom)
				(hide yes)
			)
		)
		(property "Footprint" "antmicro-footprints:R_0402_1005Metric"
			(at 86.36 114.3 0)
			(effects
				(font
					(size 1.27 1.27)
					(thickness 0.15)
				)
				(justify left bottom)
				(hide yes)
			)
		)
		(property "Datasheet" "https://www.bourns.com/docs/product-datasheets/cr.pdf"
			(at 83.82 114.3 0)
			(effects
				(font
					(size 1.27 1.27)
					(thickness 0.15)
				)
				(justify left bottom)
				(hide yes)
			)
		)
		(property "Description" "SMD Chip Resistor, 51 ohm, ± 1%, 63 mW, 0402 [1005 Metric], Thick Film, General Purpose"
			(at 101.6 93.98 0)
			(effects
				(font
					(size 1.27 1.27)
				)
				(hide yes)
			)
		)
		(property "Manufacturer" "Bourns"
			(at 78.74 114.3 0)
			(effects
				(font
					(size 1.27 1.27)
					(thickness 0.15)
				)
				(justify left bottom)
				(hide yes)
			)
		)
		(property "MPN" "CR0402-FX-51R0GLF"
			(at 81.28 114.3 0)
			(effects
				(font
					(size 1.27 1.27)
					(thickness 0.15)
				)
				(justify left bottom)
				(hide yes)
			)
		)
		(property "Val" "51R"
			(at 103.505 97.7899 90)
			(effects
				(font
					(size 1.27 1.27)
					(thickness 0.15)
				)
				(justify left)
			)
		)
		(property "License" "Apache-2.0"
			(at 76.2 114.3 0)
			(effects
				(font
					(size 1.27 1.27)
					(thickness 0.15)
				)
				(justify left bottom)
				(hide yes)
			)
		)
		(property "Author" "Antmicro"
			(at 73.66 114.3 0)
			(effects
				(font
					(size 1.27 1.27)
					(thickness 0.15)
				)
				(justify left bottom)
				(hide yes)
			)
		)
		(property "Tolerance" "1%"
			(at 91.44 114.3 0)
			(effects
				(font
					(size 1.27 1.27)
				)
				(justify left bottom)
				(hide yes)
			)
		)
		(pin "1"
		)
		(pin "2"
		)
		(instances
			(project "artix-dc-scm"
				(path ""
					(reference "R100")
					(unit 1)
				)
			)
		)
	)
	(symbol
		(lib_id "antmicropower:GND")
		(at 101.6 67.31 0)
		(unit 1)
		(exclude_from_sim no)
		(in_bom yes)
		(on_board yes)
		(dnp no)
		(property "Reference" "#PWR0118"
			(at 101.6 73.66 0)
			(effects
				(font
					(size 1.27 1.27)
				)
				(hide yes)
			)
		)
		(property "Value" "GND"
			(at 101.6 71.12 0)
			(effects
				(font
					(size 1.27 1.27)
				)
			)
		)
		(property "Footprint" ""
			(at 101.6 67.31 0)
			(effects
				(font
					(size 1.27 1.27)
				)
				(hide yes)
			)
		)
		(property "Datasheet" ""
			(at 101.6 67.31 0)
			(effects
				(font
					(size 1.27 1.27)
				)
				(hide yes)
			)
		)
		(property "Description" ""
			(at 101.6 67.31 0)
			(effects
				(font
					(size 1.27 1.27)
				)
				(hide yes)
			)
		)
		(property "Author" "Antmicro"
			(at 110.49 74.93 0)
			(effects
				(font
					(size 1.27 1.27)
					(thickness 0.15)
				)
				(justify left bottom)
				(hide yes)
			)
		)
		(property "License" "Apache-2.0"
			(at 110.49 77.47 0)
			(effects
				(font
					(size 1.27 1.27)
					(thickness 0.15)
				)
				(justify left bottom)
				(hide yes)
			)
		)
		(pin "1"
		)
		(instances
			(project "artix-dc-scm"
				(path ""
					(reference "#PWR0118")
					(unit 1)
				)
			)
		)
	)
	(symbol
		(lib_id "antmicroResistors0402:R_4k7_0402")
		(at 101.6 62.23 270)
		(unit 1)
		(exclude_from_sim no)
		(in_bom yes)
		(on_board yes)
		(dnp no)
		(property "Reference" "R13"
			(at 102.87 63.5 90)
			(effects
				(font
					(size 1.27 1.27)
				)
				(justify left)
			)
		)
		(property "Value" "R_4k7_0402"
			(at 88.9 82.55 0)
			(effects
				(font
					(size 1.27 1.27)
					(thickness 0.15)
				)
				(justify left bottom)
				(hide yes)
			)
		)
		(property "Footprint" "antmicro-footprints:R_0402_1005Metric"
			(at 86.36 82.55 0)
			(effects
				(font
					(size 1.27 1.27)
					(thickness 0.15)
				)
				(justify left bottom)
				(hide yes)
			)
		)
		(property "Datasheet" "https://www.bourns.com/docs/product-datasheets/cr.pdf"
			(at 83.82 82.55 0)
			(effects
				(font
					(size 1.27 1.27)
					(thickness 0.15)
				)
				(justify left bottom)
				(hide yes)
			)
		)
		(property "Description" "SMD Chip Resistor, 4.7 kohm, ± 1%, 62.5 mW, 0402 [1005 Metric], Thick Film, General Purpose"
			(at 101.6 62.23 0)
			(effects
				(font
					(size 1.27 1.27)
				)
				(hide yes)
			)
		)
		(property "Manufacturer" "Bourns"
			(at 78.74 82.55 0)
			(effects
				(font
					(size 1.27 1.27)
					(thickness 0.15)
				)
				(justify left bottom)
				(hide yes)
			)
		)
		(property "MPN" "CR0402-FX-4701GLF"
			(at 81.28 82.55 0)
			(effects
				(font
					(size 1.27 1.27)
					(thickness 0.15)
				)
				(justify left bottom)
				(hide yes)
			)
		)
		(property "Val" "4k7"
			(at 102.87 66.04 90)
			(effects
				(font
					(size 1.27 1.27)
					(thickness 0.15)
				)
				(justify left)
			)
		)
		(property "License" "Apache-2.0"
			(at 76.2 82.55 0)
			(effects
				(font
					(size 1.27 1.27)
					(thickness 0.15)
				)
				(justify left bottom)
				(hide yes)
			)
		)
		(property "Author" "Antmicro"
			(at 73.66 82.55 0)
			(effects
				(font
					(size 1.27 1.27)
					(thickness 0.15)
				)
				(justify left bottom)
				(hide yes)
			)
		)
		(property "Tolerance" "1%"
			(at 91.44 82.55 0)
			(effects
				(font
					(size 1.27 1.27)
				)
				(justify left bottom)
				(hide yes)
			)
		)
		(pin "1"
		)
		(pin "2"
		)
		(instances
			(project "artix-dc-scm"
				(path ""
					(reference "R13")
					(unit 1)
				)
			)
		)
	)
	(symbol
		(lib_id "antmicroCapacitors0402:C_4u7_0402")
		(at 130.81 44.45 90)
		(unit 1)
		(exclude_from_sim no)
		(in_bom yes)
		(on_board yes)
		(dnp no)
		(property "Reference" "C48"
			(at 131.445 40.005 90)
			(effects
				(font
					(size 1.27 1.27)
				)
				(justify right)
			)
		)
		(property "Value" "C_4u7_0402"
			(at 140.97 24.13 0)
			(effects
				(font
					(size 1.27 1.27)
					(thickness 0.15)
				)
				(justify left bottom)
				(hide yes)
			)
		)
		(property "Footprint" "antmicro-footprints:C_0402_1005Metric"
			(at 143.51 24.13 0)
			(effects
				(font
					(size 1.27 1.27)
					(thickness 0.15)
				)
				(justify left bottom)
				(hide yes)
			)
		)
		(property "Datasheet" "https://www.murata.com/products/productdetail?partno=GRM155R61A475MEAA%23"
			(at 146.05 24.13 0)
			(effects
				(font
					(size 1.27 1.27)
					(thickness 0.15)
				)
				(justify left bottom)
				(hide yes)
			)
		)
		(property "Description" "SMD Multilayer Ceramic Capacitor, 4.7 µF, 10 V, 0402 [1005 Metric], ± 20%, X5R, GRM Series"
			(at 130.81 44.45 0)
			(effects
				(font
					(size 1.27 1.27)
				)
				(hide yes)
			)
		)
		(property "Manufacturer" "Murata"
			(at 151.13 24.13 0)
			(effects
				(font
					(size 1.27 1.27)
					(thickness 0.15)
				)
				(justify left bottom)
				(hide yes)
			)
		)
		(property "MPN" "GRM155R61A475MEAAD"
			(at 148.59 24.13 0)
			(effects
				(font
					(size 1.27 1.27)
					(thickness 0.15)
				)
				(justify left bottom)
				(hide yes)
			)
		)
		(property "Val" "4u7"
			(at 131.445 43.815 90)
			(effects
				(font
					(size 1.27 1.27)
					(thickness 0.15)
				)
				(justify right)
			)
		)
		(property "License" "Apache-2.0"
			(at 153.67 24.13 0)
			(effects
				(font
					(size 1.27 1.27)
					(thickness 0.15)
				)
				(justify left bottom)
				(hide yes)
			)
		)
		(property "Author" "Antmicro"
			(at 156.21 24.13 0)
			(effects
				(font
					(size 1.27 1.27)
					(thickness 0.15)
				)
				(justify left bottom)
				(hide yes)
			)
		)
		(property "Voltage" ""
			(at 158.75 24.13 0)
			(effects
				(font
					(size 1.27 1.27)
				)
				(justify left bottom)
				(hide yes)
			)
		)
		(property "Dielectric" ""
			(at 161.29 24.13 0)
			(effects
				(font
					(size 1.27 1.27)
				)
				(justify left bottom)
				(hide yes)
			)
		)
		(pin "1"
		)
		(pin "2"
		)
		(instances
			(project "artix-dc-scm"
				(path ""
					(reference "C48")
					(unit 1)
				)
			)
		)
	)
	(symbol
		(lib_id "antmicroResistors0402:R_10k_0402")
		(at 114.3 191.77 270)
		(mirror x)
		(unit 1)
		(exclude_from_sim no)
		(in_bom yes)
		(on_board yes)
		(dnp no)
		(property "Reference" "R113"
			(at 115.57 187.96 90)
			(effects
				(font
					(size 1.27 1.27)
				)
				(justify left)
			)
		)
		(property "Value" "R_10k_0402"
			(at 101.6 171.45 0)
			(effects
				(font
					(size 1.27 1.27)
					(thickness 0.15)
				)
				(justify left bottom)
				(hide yes)
			)
		)
		(property "Footprint" "antmicro-footprints:R_0402_1005Metric"
			(at 99.06 171.45 0)
			(effects
				(font
					(size 1.27 1.27)
					(thickness 0.15)
				)
				(justify left bottom)
				(hide yes)
			)
		)
		(property "Datasheet" "https://www.bourns.com/docs/product-datasheets/cr.pdf"
			(at 96.52 171.45 0)
			(effects
				(font
					(size 1.27 1.27)
					(thickness 0.15)
				)
				(justify left bottom)
				(hide yes)
			)
		)
		(property "Description" "SMD Chip Resistor, 10 kohm, ± 1%, 62.5 mW, 0402 [1005 Metric], Thick Film, General Purpose"
			(at 114.3 191.77 0)
			(effects
				(font
					(size 1.27 1.27)
				)
				(hide yes)
			)
		)
		(property "Manufacturer" "Bourns"
			(at 91.44 171.45 0)
			(effects
				(font
					(size 1.27 1.27)
					(thickness 0.15)
				)
				(justify left bottom)
				(hide yes)
			)
		)
		(property "MPN" "CR0402-FX-1002GLF"
			(at 93.98 171.45 0)
			(effects
				(font
					(size 1.27 1.27)
					(thickness 0.15)
				)
				(justify left bottom)
				(hide yes)
			)
		)
		(property "Val" "10k"
			(at 115.57 190.5 90)
			(effects
				(font
					(size 1.27 1.27)
					(thickness 0.15)
				)
				(justify left)
			)
		)
		(property "License" "Apache-2.0"
			(at 88.9 171.45 0)
			(effects
				(font
					(size 1.27 1.27)
					(thickness 0.15)
				)
				(justify left bottom)
				(hide yes)
			)
		)
		(property "Author" "Antmicro"
			(at 86.36 171.45 0)
			(effects
				(font
					(size 1.27 1.27)
					(thickness 0.15)
				)
				(justify left bottom)
				(hide yes)
			)
		)
		(property "Tolerance" "1%"
			(at 104.14 171.45 0)
			(effects
				(font
					(size 1.27 1.27)
				)
				(justify left bottom)
				(hide yes)
			)
		)
		(pin "1"
		)
		(pin "2"
		)
		(instances
			(project "artix-dc-scm"
				(path ""
					(reference "R113")
					(unit 1)
				)
			)
		)
	)
	(symbol
		(lib_id "antmicroCapacitors0402:C_470n_0402")
		(at 185.42 44.45 90)
		(unit 1)
		(exclude_from_sim no)
		(in_bom yes)
		(on_board yes)
		(dnp no)
		(property "Reference" "C8"
			(at 186.055 40.005 90)
			(effects
				(font
					(size 1.27 1.27)
				)
				(justify right)
			)
		)
		(property "Value" "C_470n_0402"
			(at 195.58 24.13 0)
			(effects
				(font
					(size 1.27 1.27)
					(thickness 0.15)
				)
				(justify left bottom)
				(hide yes)
			)
		)
		(property "Footprint" "antmicro-footprints:C_0402_1005Metric"
			(at 198.12 24.13 0)
			(effects
				(font
					(size 1.27 1.27)
					(thickness 0.15)
				)
				(justify left bottom)
				(hide yes)
			)
		)
		(property "Datasheet" "https://product.tdk.com/en/search/capacitor/ceramic/mlcc/info?part_no=C1005X5R1E474M050BB"
			(at 200.66 24.13 0)
			(effects
				(font
					(size 1.27 1.27)
					(thickness 0.15)
				)
				(justify left bottom)
				(hide yes)
			)
		)
		(property "Description" "SMD Multilayer Ceramic Capacitor, 0.47 µF, 25 V, 0402 [1005 Metric], ± 20%, X5R, C"
			(at 185.42 44.45 0)
			(effects
				(font
					(size 1.27 1.27)
				)
				(hide yes)
			)
		)
		(property "Manufacturer" "TDK"
			(at 205.74 24.13 0)
			(effects
				(font
					(size 1.27 1.27)
					(thickness 0.15)
				)
				(justify left bottom)
				(hide yes)
			)
		)
		(property "MPN" "C1005X5R1E474M050BB"
			(at 203.2 24.13 0)
			(effects
				(font
					(size 1.27 1.27)
					(thickness 0.15)
				)
				(justify left bottom)
				(hide yes)
			)
		)
		(property "Val" "470n"
			(at 186.055 43.815 90)
			(effects
				(font
					(size 1.27 1.27)
					(thickness 0.15)
				)
				(justify right)
			)
		)
		(property "License" "Apache-2.0"
			(at 208.28 24.13 0)
			(effects
				(font
					(size 1.27 1.27)
					(thickness 0.15)
				)
				(justify left bottom)
				(hide yes)
			)
		)
		(property "Author" "Antmicro"
			(at 210.82 24.13 0)
			(effects
				(font
					(size 1.27 1.27)
					(thickness 0.15)
				)
				(justify left bottom)
				(hide yes)
			)
		)
		(property "Voltage" ""
			(at 213.36 24.13 0)
			(effects
				(font
					(size 1.27 1.27)
				)
				(justify left bottom)
				(hide yes)
			)
		)
		(property "Dielectric" ""
			(at 215.9 24.13 0)
			(effects
				(font
					(size 1.27 1.27)
				)
				(justify left bottom)
				(hide yes)
			)
		)
		(pin "1"
		)
		(pin "2"
		)
		(instances
			(project "artix-dc-scm"
				(path ""
					(reference "C8")
					(unit 1)
				)
			)
		)
	)
	(symbol
		(lib_id "antmicroCapacitors0402:C_10u_0402")
		(at 185.42 201.93 90)
		(unit 1)
		(exclude_from_sim no)
		(in_bom yes)
		(on_board yes)
		(dnp no)
		(property "Reference" "C155"
			(at 186.055 197.485 90)
			(effects
				(font
					(size 1.27 1.27)
				)
				(justify right)
			)
		)
		(property "Value" "C_10u_0402"
			(at 195.58 181.61 0)
			(effects
				(font
					(size 1.27 1.27)
					(thickness 0.15)
				)
				(justify left bottom)
				(hide yes)
			)
		)
		(property "Footprint" "antmicro-footprints:C_0402_1005Metric"
			(at 198.12 181.61 0)
			(effects
				(font
					(size 1.27 1.27)
					(thickness 0.15)
				)
				(justify left bottom)
				(hide yes)
			)
		)
		(property "Datasheet" "https://www.yageo.com/en/Chart/Download/pdf/CC0402MRX5R5BB106"
			(at 200.66 181.61 0)
			(effects
				(font
					(size 1.27 1.27)
					(thickness 0.15)
				)
				(justify left bottom)
				(hide yes)
			)
		)
		(property "Description" "SMD Multilayer Ceramic Capacitor, 10 µF, 6.3 V, 0402 [1005 Metric], ± 20%, X5R, CC Series"
			(at 185.42 201.93 0)
			(effects
				(font
					(size 1.27 1.27)
				)
				(hide yes)
			)
		)
		(property "Manufacturer" "YAGEO"
			(at 205.74 181.61 0)
			(effects
				(font
					(size 1.27 1.27)
					(thickness 0.15)
				)
				(justify left bottom)
				(hide yes)
			)
		)
		(property "MPN" "CC0402MRX5R5BB106"
			(at 203.2 181.61 0)
			(effects
				(font
					(size 1.27 1.27)
					(thickness 0.15)
				)
				(justify left bottom)
				(hide yes)
			)
		)
		(property "Val" "10u"
			(at 186.055 201.295 90)
			(effects
				(font
					(size 1.27 1.27)
					(thickness 0.15)
				)
				(justify right)
			)
		)
		(property "License" "Apache-2.0"
			(at 208.28 181.61 0)
			(effects
				(font
					(size 1.27 1.27)
					(thickness 0.15)
				)
				(justify left bottom)
				(hide yes)
			)
		)
		(property "Author" "Antmicro"
			(at 210.82 181.61 0)
			(effects
				(font
					(size 1.27 1.27)
					(thickness 0.15)
				)
				(justify left bottom)
				(hide yes)
			)
		)
		(property "Voltage" ""
			(at 213.36 181.61 0)
			(effects
				(font
					(size 1.27 1.27)
				)
				(justify left bottom)
				(hide yes)
			)
		)
		(property "Dielectric" ""
			(at 215.9 181.61 0)
			(effects
				(font
					(size 1.27 1.27)
				)
				(justify left bottom)
				(hide yes)
			)
		)
		(pin "1"
		)
		(pin "2"
		)
		(instances
			(project "artix-dc-scm"
				(path ""
					(reference "C155")
					(unit 1)
				)
			)
		)
	)
	(symbol
		(lib_id "antmicroCapacitors0402:C_470n_0402")
		(at 191.77 44.45 90)
		(unit 1)
		(exclude_from_sim no)
		(in_bom yes)
		(on_board yes)
		(dnp no)
		(property "Reference" "C9"
			(at 192.405 40.005 90)
			(effects
				(font
					(size 1.27 1.27)
				)
				(justify right)
			)
		)
		(property "Value" "C_470n_0402"
			(at 201.93 24.13 0)
			(effects
				(font
					(size 1.27 1.27)
					(thickness 0.15)
				)
				(justify left bottom)
				(hide yes)
			)
		)
		(property "Footprint" "antmicro-footprints:C_0402_1005Metric"
			(at 204.47 24.13 0)
			(effects
				(font
					(size 1.27 1.27)
					(thickness 0.15)
				)
				(justify left bottom)
				(hide yes)
			)
		)
		(property "Datasheet" "https://product.tdk.com/en/search/capacitor/ceramic/mlcc/info?part_no=C1005X5R1E474M050BB"
			(at 207.01 24.13 0)
			(effects
				(font
					(size 1.27 1.27)
					(thickness 0.15)
				)
				(justify left bottom)
				(hide yes)
			)
		)
		(property "Description" "SMD Multilayer Ceramic Capacitor, 0.47 µF, 25 V, 0402 [1005 Metric], ± 20%, X5R, C"
			(at 191.77 44.45 0)
			(effects
				(font
					(size 1.27 1.27)
				)
				(hide yes)
			)
		)
		(property "Manufacturer" "TDK"
			(at 212.09 24.13 0)
			(effects
				(font
					(size 1.27 1.27)
					(thickness 0.15)
				)
				(justify left bottom)
				(hide yes)
			)
		)
		(property "MPN" "C1005X5R1E474M050BB"
			(at 209.55 24.13 0)
			(effects
				(font
					(size 1.27 1.27)
					(thickness 0.15)
				)
				(justify left bottom)
				(hide yes)
			)
		)
		(property "Val" "470n"
			(at 192.405 43.815 90)
			(effects
				(font
					(size 1.27 1.27)
					(thickness 0.15)
				)
				(justify right)
			)
		)
		(property "License" "Apache-2.0"
			(at 214.63 24.13 0)
			(effects
				(font
					(size 1.27 1.27)
					(thickness 0.15)
				)
				(justify left bottom)
				(hide yes)
			)
		)
		(property "Author" "Antmicro"
			(at 217.17 24.13 0)
			(effects
				(font
					(size 1.27 1.27)
					(thickness 0.15)
				)
				(justify left bottom)
				(hide yes)
			)
		)
		(property "Voltage" ""
			(at 219.71 24.13 0)
			(effects
				(font
					(size 1.27 1.27)
				)
				(justify left bottom)
				(hide yes)
			)
		)
		(property "Dielectric" ""
			(at 222.25 24.13 0)
			(effects
				(font
					(size 1.27 1.27)
				)
				(justify left bottom)
				(hide yes)
			)
		)
		(pin "1"
		)
		(pin "2"
		)
		(instances
			(project "artix-dc-scm"
				(path ""
					(reference "C9")
					(unit 1)
				)
			)
		)
	)
	(symbol
		(lib_id "antmicroCapacitors0402:C_470n_0402")
		(at 139.7 44.45 90)
		(unit 1)
		(exclude_from_sim no)
		(in_bom yes)
		(on_board yes)
		(dnp no)
		(property "Reference" "C49"
			(at 140.335 40.005 90)
			(effects
				(font
					(size 1.27 1.27)
				)
				(justify right)
			)
		)
		(property "Value" "C_470n_0402"
			(at 149.86 24.13 0)
			(effects
				(font
					(size 1.27 1.27)
					(thickness 0.15)
				)
				(justify left bottom)
				(hide yes)
			)
		)
		(property "Footprint" "antmicro-footprints:C_0402_1005Metric"
			(at 152.4 24.13 0)
			(effects
				(font
					(size 1.27 1.27)
					(thickness 0.15)
				)
				(justify left bottom)
				(hide yes)
			)
		)
		(property "Datasheet" "https://product.tdk.com/en/search/capacitor/ceramic/mlcc/info?part_no=C1005X5R1E474M050BB"
			(at 154.94 24.13 0)
			(effects
				(font
					(size 1.27 1.27)
					(thickness 0.15)
				)
				(justify left bottom)
				(hide yes)
			)
		)
		(property "Description" "SMD Multilayer Ceramic Capacitor, 0.47 µF, 25 V, 0402 [1005 Metric], ± 20%, X5R, C"
			(at 139.7 44.45 0)
			(effects
				(font
					(size 1.27 1.27)
				)
				(hide yes)
			)
		)
		(property "Manufacturer" "TDK"
			(at 160.02 24.13 0)
			(effects
				(font
					(size 1.27 1.27)
					(thickness 0.15)
				)
				(justify left bottom)
				(hide yes)
			)
		)
		(property "MPN" "C1005X5R1E474M050BB"
			(at 157.48 24.13 0)
			(effects
				(font
					(size 1.27 1.27)
					(thickness 0.15)
				)
				(justify left bottom)
				(hide yes)
			)
		)
		(property "Val" "470n"
			(at 140.335 43.815 90)
			(effects
				(font
					(size 1.27 1.27)
					(thickness 0.15)
				)
				(justify right)
			)
		)
		(property "License" "Apache-2.0"
			(at 162.56 24.13 0)
			(effects
				(font
					(size 1.27 1.27)
					(thickness 0.15)
				)
				(justify left bottom)
				(hide yes)
			)
		)
		(property "Author" "Antmicro"
			(at 165.1 24.13 0)
			(effects
				(font
					(size 1.27 1.27)
					(thickness 0.15)
				)
				(justify left bottom)
				(hide yes)
			)
		)
		(property "Voltage" ""
			(at 167.64 24.13 0)
			(effects
				(font
					(size 1.27 1.27)
				)
				(justify left bottom)
				(hide yes)
			)
		)
		(property "Dielectric" ""
			(at 170.18 24.13 0)
			(effects
				(font
					(size 1.27 1.27)
				)
				(justify left bottom)
				(hide yes)
			)
		)
		(pin "1"
		)
		(pin "2"
		)
		(instances
			(project "artix-dc-scm"
				(path ""
					(reference "C49")
					(unit 1)
				)
			)
		)
	)
	(symbol
		(lib_id "antmicroCapacitors0402:C_470n_0402")
		(at 147.32 44.45 90)
		(unit 1)
		(exclude_from_sim no)
		(in_bom yes)
		(on_board yes)
		(dnp no)
		(property "Reference" "C51"
			(at 147.955 40.005 90)
			(effects
				(font
					(size 1.27 1.27)
				)
				(justify right)
			)
		)
		(property "Value" "C_470n_0402"
			(at 157.48 24.13 0)
			(effects
				(font
					(size 1.27 1.27)
					(thickness 0.15)
				)
				(justify left bottom)
				(hide yes)
			)
		)
		(property "Footprint" "antmicro-footprints:C_0402_1005Metric"
			(at 160.02 24.13 0)
			(effects
				(font
					(size 1.27 1.27)
					(thickness 0.15)
				)
				(justify left bottom)
				(hide yes)
			)
		)
		(property "Datasheet" "https://product.tdk.com/en/search/capacitor/ceramic/mlcc/info?part_no=C1005X5R1E474M050BB"
			(at 162.56 24.13 0)
			(effects
				(font
					(size 1.27 1.27)
					(thickness 0.15)
				)
				(justify left bottom)
				(hide yes)
			)
		)
		(property "Description" "SMD Multilayer Ceramic Capacitor, 0.47 µF, 25 V, 0402 [1005 Metric], ± 20%, X5R, C"
			(at 147.32 44.45 0)
			(effects
				(font
					(size 1.27 1.27)
				)
				(hide yes)
			)
		)
		(property "Manufacturer" "TDK"
			(at 167.64 24.13 0)
			(effects
				(font
					(size 1.27 1.27)
					(thickness 0.15)
				)
				(justify left bottom)
				(hide yes)
			)
		)
		(property "MPN" "C1005X5R1E474M050BB"
			(at 165.1 24.13 0)
			(effects
				(font
					(size 1.27 1.27)
					(thickness 0.15)
				)
				(justify left bottom)
				(hide yes)
			)
		)
		(property "Val" "470n"
			(at 147.955 43.815 90)
			(effects
				(font
					(size 1.27 1.27)
					(thickness 0.15)
				)
				(justify right)
			)
		)
		(property "License" "Apache-2.0"
			(at 170.18 24.13 0)
			(effects
				(font
					(size 1.27 1.27)
					(thickness 0.15)
				)
				(justify left bottom)
				(hide yes)
			)
		)
		(property "Author" "Antmicro"
			(at 172.72 24.13 0)
			(effects
				(font
					(size 1.27 1.27)
					(thickness 0.15)
				)
				(justify left bottom)
				(hide yes)
			)
		)
		(property "Voltage" ""
			(at 175.26 24.13 0)
			(effects
				(font
					(size 1.27 1.27)
				)
				(justify left bottom)
				(hide yes)
			)
		)
		(property "Dielectric" ""
			(at 177.8 24.13 0)
			(effects
				(font
					(size 1.27 1.27)
				)
				(justify left bottom)
				(hide yes)
			)
		)
		(pin "1"
		)
		(pin "2"
		)
		(instances
			(project "artix-dc-scm"
				(path ""
					(reference "C51")
					(unit 1)
				)
			)
		)
	)
	(symbol
		(lib_id "antmicroCapacitors0402:C_470n_0402")
		(at 154.94 44.45 90)
		(unit 1)
		(exclude_from_sim no)
		(in_bom yes)
		(on_board yes)
		(dnp no)
		(property "Reference" "C53"
			(at 155.575 40.005 90)
			(effects
				(font
					(size 1.27 1.27)
				)
				(justify right)
			)
		)
		(property "Value" "C_470n_0402"
			(at 165.1 24.13 0)
			(effects
				(font
					(size 1.27 1.27)
					(thickness 0.15)
				)
				(justify left bottom)
				(hide yes)
			)
		)
		(property "Footprint" "antmicro-footprints:C_0402_1005Metric"
			(at 167.64 24.13 0)
			(effects
				(font
					(size 1.27 1.27)
					(thickness 0.15)
				)
				(justify left bottom)
				(hide yes)
			)
		)
		(property "Datasheet" "https://product.tdk.com/en/search/capacitor/ceramic/mlcc/info?part_no=C1005X5R1E474M050BB"
			(at 170.18 24.13 0)
			(effects
				(font
					(size 1.27 1.27)
					(thickness 0.15)
				)
				(justify left bottom)
				(hide yes)
			)
		)
		(property "Description" "SMD Multilayer Ceramic Capacitor, 0.47 µF, 25 V, 0402 [1005 Metric], ± 20%, X5R, C"
			(at 154.94 44.45 0)
			(effects
				(font
					(size 1.27 1.27)
				)
				(hide yes)
			)
		)
		(property "Manufacturer" "TDK"
			(at 175.26 24.13 0)
			(effects
				(font
					(size 1.27 1.27)
					(thickness 0.15)
				)
				(justify left bottom)
				(hide yes)
			)
		)
		(property "MPN" "C1005X5R1E474M050BB"
			(at 172.72 24.13 0)
			(effects
				(font
					(size 1.27 1.27)
					(thickness 0.15)
				)
				(justify left bottom)
				(hide yes)
			)
		)
		(property "Val" "470n"
			(at 155.575 43.815 90)
			(effects
				(font
					(size 1.27 1.27)
					(thickness 0.15)
				)
				(justify right)
			)
		)
		(property "License" "Apache-2.0"
			(at 177.8 24.13 0)
			(effects
				(font
					(size 1.27 1.27)
					(thickness 0.15)
				)
				(justify left bottom)
				(hide yes)
			)
		)
		(property "Author" "Antmicro"
			(at 180.34 24.13 0)
			(effects
				(font
					(size 1.27 1.27)
					(thickness 0.15)
				)
				(justify left bottom)
				(hide yes)
			)
		)
		(property "Voltage" ""
			(at 182.88 24.13 0)
			(effects
				(font
					(size 1.27 1.27)
				)
				(justify left bottom)
				(hide yes)
			)
		)
		(property "Dielectric" ""
			(at 185.42 24.13 0)
			(effects
				(font
					(size 1.27 1.27)
				)
				(justify left bottom)
				(hide yes)
			)
		)
		(pin "1"
		)
		(pin "2"
		)
		(instances
			(project "artix-dc-scm"
				(path ""
					(reference "C53")
					(unit 1)
				)
			)
		)
	)
	(symbol
		(lib_id "antmicroCapacitors0402:C_470n_0402")
		(at 162.56 44.45 90)
		(unit 1)
		(exclude_from_sim no)
		(in_bom yes)
		(on_board yes)
		(dnp no)
		(property "Reference" "C55"
			(at 163.195 40.005 90)
			(effects
				(font
					(size 1.27 1.27)
				)
				(justify right)
			)
		)
		(property "Value" "C_470n_0402"
			(at 172.72 24.13 0)
			(effects
				(font
					(size 1.27 1.27)
					(thickness 0.15)
				)
				(justify left bottom)
				(hide yes)
			)
		)
		(property "Footprint" "antmicro-footprints:C_0402_1005Metric"
			(at 175.26 24.13 0)
			(effects
				(font
					(size 1.27 1.27)
					(thickness 0.15)
				)
				(justify left bottom)
				(hide yes)
			)
		)
		(property "Datasheet" "https://product.tdk.com/en/search/capacitor/ceramic/mlcc/info?part_no=C1005X5R1E474M050BB"
			(at 177.8 24.13 0)
			(effects
				(font
					(size 1.27 1.27)
					(thickness 0.15)
				)
				(justify left bottom)
				(hide yes)
			)
		)
		(property "Description" "SMD Multilayer Ceramic Capacitor, 0.47 µF, 25 V, 0402 [1005 Metric], ± 20%, X5R, C"
			(at 162.56 44.45 0)
			(effects
				(font
					(size 1.27 1.27)
				)
				(hide yes)
			)
		)
		(property "Manufacturer" "TDK"
			(at 182.88 24.13 0)
			(effects
				(font
					(size 1.27 1.27)
					(thickness 0.15)
				)
				(justify left bottom)
				(hide yes)
			)
		)
		(property "MPN" "C1005X5R1E474M050BB"
			(at 180.34 24.13 0)
			(effects
				(font
					(size 1.27 1.27)
					(thickness 0.15)
				)
				(justify left bottom)
				(hide yes)
			)
		)
		(property "Val" "470n"
			(at 163.195 43.815 90)
			(effects
				(font
					(size 1.27 1.27)
					(thickness 0.15)
				)
				(justify right)
			)
		)
		(property "License" "Apache-2.0"
			(at 185.42 24.13 0)
			(effects
				(font
					(size 1.27 1.27)
					(thickness 0.15)
				)
				(justify left bottom)
				(hide yes)
			)
		)
		(property "Author" "Antmicro"
			(at 187.96 24.13 0)
			(effects
				(font
					(size 1.27 1.27)
					(thickness 0.15)
				)
				(justify left bottom)
				(hide yes)
			)
		)
		(property "Voltage" ""
			(at 190.5 24.13 0)
			(effects
				(font
					(size 1.27 1.27)
				)
				(justify left bottom)
				(hide yes)
			)
		)
		(property "Dielectric" ""
			(at 193.04 24.13 0)
			(effects
				(font
					(size 1.27 1.27)
				)
				(justify left bottom)
				(hide yes)
			)
		)
		(pin "1"
		)
		(pin "2"
		)
		(instances
			(project "artix-dc-scm"
				(path ""
					(reference "C55")
					(unit 1)
				)
			)
		)
	)
	(symbol
		(lib_id "antmicroCapacitors0402:C_470n_0402")
		(at 170.18 44.45 90)
		(unit 1)
		(exclude_from_sim no)
		(in_bom yes)
		(on_board yes)
		(dnp no)
		(property "Reference" "C58"
			(at 170.815 40.005 90)
			(effects
				(font
					(size 1.27 1.27)
				)
				(justify right)
			)
		)
		(property "Value" "C_470n_0402"
			(at 180.34 24.13 0)
			(effects
				(font
					(size 1.27 1.27)
					(thickness 0.15)
				)
				(justify left bottom)
				(hide yes)
			)
		)
		(property "Footprint" "antmicro-footprints:C_0402_1005Metric"
			(at 182.88 24.13 0)
			(effects
				(font
					(size 1.27 1.27)
					(thickness 0.15)
				)
				(justify left bottom)
				(hide yes)
			)
		)
		(property "Datasheet" "https://product.tdk.com/en/search/capacitor/ceramic/mlcc/info?part_no=C1005X5R1E474M050BB"
			(at 185.42 24.13 0)
			(effects
				(font
					(size 1.27 1.27)
					(thickness 0.15)
				)
				(justify left bottom)
				(hide yes)
			)
		)
		(property "Description" "SMD Multilayer Ceramic Capacitor, 0.47 µF, 25 V, 0402 [1005 Metric], ± 20%, X5R, C"
			(at 170.18 44.45 0)
			(effects
				(font
					(size 1.27 1.27)
				)
				(hide yes)
			)
		)
		(property "Manufacturer" "TDK"
			(at 190.5 24.13 0)
			(effects
				(font
					(size 1.27 1.27)
					(thickness 0.15)
				)
				(justify left bottom)
				(hide yes)
			)
		)
		(property "MPN" "C1005X5R1E474M050BB"
			(at 187.96 24.13 0)
			(effects
				(font
					(size 1.27 1.27)
					(thickness 0.15)
				)
				(justify left bottom)
				(hide yes)
			)
		)
		(property "Val" "470n"
			(at 170.815 43.815 90)
			(effects
				(font
					(size 1.27 1.27)
					(thickness 0.15)
				)
				(justify right)
			)
		)
		(property "License" "Apache-2.0"
			(at 193.04 24.13 0)
			(effects
				(font
					(size 1.27 1.27)
					(thickness 0.15)
				)
				(justify left bottom)
				(hide yes)
			)
		)
		(property "Author" "Antmicro"
			(at 195.58 24.13 0)
			(effects
				(font
					(size 1.27 1.27)
					(thickness 0.15)
				)
				(justify left bottom)
				(hide yes)
			)
		)
		(property "Voltage" ""
			(at 198.12 24.13 0)
			(effects
				(font
					(size 1.27 1.27)
				)
				(justify left bottom)
				(hide yes)
			)
		)
		(property "Dielectric" ""
			(at 200.66 24.13 0)
			(effects
				(font
					(size 1.27 1.27)
				)
				(justify left bottom)
				(hide yes)
			)
		)
		(pin "1"
		)
		(pin "2"
		)
		(instances
			(project "artix-dc-scm"
				(path ""
					(reference "C58")
					(unit 1)
				)
			)
		)
	)
	(symbol
		(lib_id "antmicroCapacitors0402:C_470n_0402")
		(at 177.8 44.45 90)
		(unit 1)
		(exclude_from_sim no)
		(in_bom yes)
		(on_board yes)
		(dnp no)
		(property "Reference" "C60"
			(at 178.435 40.005 90)
			(effects
				(font
					(size 1.27 1.27)
				)
				(justify right)
			)
		)
		(property "Value" "C_470n_0402"
			(at 187.96 24.13 0)
			(effects
				(font
					(size 1.27 1.27)
					(thickness 0.15)
				)
				(justify left bottom)
				(hide yes)
			)
		)
		(property "Footprint" "antmicro-footprints:C_0402_1005Metric"
			(at 190.5 24.13 0)
			(effects
				(font
					(size 1.27 1.27)
					(thickness 0.15)
				)
				(justify left bottom)
				(hide yes)
			)
		)
		(property "Datasheet" "https://product.tdk.com/en/search/capacitor/ceramic/mlcc/info?part_no=C1005X5R1E474M050BB"
			(at 193.04 24.13 0)
			(effects
				(font
					(size 1.27 1.27)
					(thickness 0.15)
				)
				(justify left bottom)
				(hide yes)
			)
		)
		(property "Description" "SMD Multilayer Ceramic Capacitor, 0.47 µF, 25 V, 0402 [1005 Metric], ± 20%, X5R, C"
			(at 177.8 44.45 0)
			(effects
				(font
					(size 1.27 1.27)
				)
				(hide yes)
			)
		)
		(property "Manufacturer" "TDK"
			(at 198.12 24.13 0)
			(effects
				(font
					(size 1.27 1.27)
					(thickness 0.15)
				)
				(justify left bottom)
				(hide yes)
			)
		)
		(property "MPN" "C1005X5R1E474M050BB"
			(at 195.58 24.13 0)
			(effects
				(font
					(size 1.27 1.27)
					(thickness 0.15)
				)
				(justify left bottom)
				(hide yes)
			)
		)
		(property "Val" "470n"
			(at 178.435 43.815 90)
			(effects
				(font
					(size 1.27 1.27)
					(thickness 0.15)
				)
				(justify right)
			)
		)
		(property "License" "Apache-2.0"
			(at 200.66 24.13 0)
			(effects
				(font
					(size 1.27 1.27)
					(thickness 0.15)
				)
				(justify left bottom)
				(hide yes)
			)
		)
		(property "Author" "Antmicro"
			(at 203.2 24.13 0)
			(effects
				(font
					(size 1.27 1.27)
					(thickness 0.15)
				)
				(justify left bottom)
				(hide yes)
			)
		)
		(property "Voltage" ""
			(at 205.74 24.13 0)
			(effects
				(font
					(size 1.27 1.27)
				)
				(justify left bottom)
				(hide yes)
			)
		)
		(property "Dielectric" ""
			(at 208.28 24.13 0)
			(effects
				(font
					(size 1.27 1.27)
				)
				(justify left bottom)
				(hide yes)
			)
		)
		(pin "1"
		)
		(pin "2"
		)
		(instances
			(project "artix-dc-scm"
				(path ""
					(reference "C60")
					(unit 1)
				)
			)
		)
	)
	(symbol
		(lib_id "antmicroCapacitors0402:C_1n_0402")
		(at 114.3 210.82 270)
		(mirror x)
		(unit 1)
		(exclude_from_sim no)
		(in_bom yes)
		(on_board yes)
		(dnp no)
		(property "Reference" "C1"
			(at 114.935 206.375 90)
			(effects
				(font
					(size 1.27 1.27)
				)
				(justify left)
			)
		)
		(property "Value" "C_1n_0402"
			(at 104.14 190.5 0)
			(effects
				(font
					(size 1.27 1.27)
					(thickness 0.15)
				)
				(justify left bottom)
				(hide yes)
			)
		)
		(property "Footprint" "antmicro-footprints:C_0402_1005Metric"
			(at 101.6 190.5 0)
			(effects
				(font
					(size 1.27 1.27)
					(thickness 0.15)
				)
				(justify left bottom)
				(hide yes)
			)
		)
		(property "Datasheet" "https://www.murata.com/products/productdetail?partno=GRM1555C1H102JA01%23"
			(at 99.06 190.5 0)
			(effects
				(font
					(size 1.27 1.27)
					(thickness 0.15)
				)
				(justify left bottom)
				(hide yes)
			)
		)
		(property "Description" "SMD Multilayer Ceramic Capacitor, 1000 pF, 50 V, 0402 [1005 Metric], ± 5%, C0G / NP0, GRM Series"
			(at 114.3 210.82 0)
			(effects
				(font
					(size 1.27 1.27)
				)
				(hide yes)
			)
		)
		(property "Manufacturer" "Murata"
			(at 93.98 190.5 0)
			(effects
				(font
					(size 1.27 1.27)
					(thickness 0.15)
				)
				(justify left bottom)
				(hide yes)
			)
		)
		(property "MPN" "GRM1555C1H102JA01D"
			(at 96.52 190.5 0)
			(effects
				(font
					(size 1.27 1.27)
					(thickness 0.15)
				)
				(justify left bottom)
				(hide yes)
			)
		)
		(property "Val" "1n"
			(at 114.935 210.185 90)
			(effects
				(font
					(size 1.27 1.27)
					(thickness 0.15)
				)
				(justify left)
			)
		)
		(property "License" "Apache-2.0"
			(at 91.44 190.5 0)
			(effects
				(font
					(size 1.27 1.27)
					(thickness 0.15)
				)
				(justify left bottom)
				(hide yes)
			)
		)
		(property "Author" "Antmicro"
			(at 88.9 190.5 0)
			(effects
				(font
					(size 1.27 1.27)
					(thickness 0.15)
				)
				(justify left bottom)
				(hide yes)
			)
		)
		(property "Voltage" "50V"
			(at 86.36 190.5 0)
			(effects
				(font
					(size 1.27 1.27)
				)
				(justify left bottom)
				(hide yes)
			)
		)
		(property "Dielectric" "C0G"
			(at 83.82 190.5 0)
			(effects
				(font
					(size 1.27 1.27)
				)
				(justify left bottom)
				(hide yes)
			)
		)
		(pin "1"
		)
		(pin "2"
		)
		(instances
			(project "artix-dc-scm"
				(path ""
					(reference "C1")
					(unit 1)
				)
			)
		)
	)
	(symbol
		(lib_id "antmicropower:GND")
		(at 114.3 213.36 0)
		(unit 1)
		(exclude_from_sim no)
		(in_bom yes)
		(on_board yes)
		(dnp no)
		(property "Reference" "#PWR03"
			(at 114.3 219.71 0)
			(effects
				(font
					(size 1.27 1.27)
				)
				(hide yes)
			)
		)
		(property "Value" "GND"
			(at 114.3 217.17 0)
			(effects
				(font
					(size 1.27 1.27)
				)
			)
		)
		(property "Footprint" ""
			(at 114.3 213.36 0)
			(effects
				(font
					(size 1.27 1.27)
				)
				(hide yes)
			)
		)
		(property "Datasheet" ""
			(at 114.3 213.36 0)
			(effects
				(font
					(size 1.27 1.27)
				)
				(hide yes)
			)
		)
		(property "Description" ""
			(at 114.3 213.36 0)
			(effects
				(font
					(size 1.27 1.27)
				)
				(hide yes)
			)
		)
		(property "Author" "Antmicro"
			(at 123.19 220.98 0)
			(effects
				(font
					(size 1.27 1.27)
					(thickness 0.15)
				)
				(justify left bottom)
				(hide yes)
			)
		)
		(property "License" "Apache-2.0"
			(at 123.19 223.52 0)
			(effects
				(font
					(size 1.27 1.27)
					(thickness 0.15)
				)
				(justify left bottom)
				(hide yes)
			)
		)
		(pin "1"
		)
		(instances
			(project "artix-dc-scm"
				(path ""
					(reference "#PWR03")
					(unit 1)
				)
			)
		)
	)
	(symbol
		(lib_id "antmicroCapacitors0402:C_470n_0402")
		(at 139.7 58.42 90)
		(unit 1)
		(exclude_from_sim no)
		(in_bom yes)
		(on_board yes)
		(dnp no)
		(property "Reference" "C50"
			(at 140.335 53.975 90)
			(effects
				(font
					(size 1.27 1.27)
				)
				(justify right)
			)
		)
		(property "Value" "C_470n_0402"
			(at 149.86 38.1 0)
			(effects
				(font
					(size 1.27 1.27)
					(thickness 0.15)
				)
				(justify left bottom)
				(hide yes)
			)
		)
		(property "Footprint" "antmicro-footprints:C_0402_1005Metric"
			(at 152.4 38.1 0)
			(effects
				(font
					(size 1.27 1.27)
					(thickness 0.15)
				)
				(justify left bottom)
				(hide yes)
			)
		)
		(property "Datasheet" "https://product.tdk.com/en/search/capacitor/ceramic/mlcc/info?part_no=C1005X5R1E474M050BB"
			(at 154.94 38.1 0)
			(effects
				(font
					(size 1.27 1.27)
					(thickness 0.15)
				)
				(justify left bottom)
				(hide yes)
			)
		)
		(property "Description" "SMD Multilayer Ceramic Capacitor, 0.47 µF, 25 V, 0402 [1005 Metric], ± 20%, X5R, C"
			(at 139.7 58.42 0)
			(effects
				(font
					(size 1.27 1.27)
				)
				(hide yes)
			)
		)
		(property "Manufacturer" "TDK"
			(at 160.02 38.1 0)
			(effects
				(font
					(size 1.27 1.27)
					(thickness 0.15)
				)
				(justify left bottom)
				(hide yes)
			)
		)
		(property "MPN" "C1005X5R1E474M050BB"
			(at 157.48 38.1 0)
			(effects
				(font
					(size 1.27 1.27)
					(thickness 0.15)
				)
				(justify left bottom)
				(hide yes)
			)
		)
		(property "Val" "470n"
			(at 140.335 57.785 90)
			(effects
				(font
					(size 1.27 1.27)
					(thickness 0.15)
				)
				(justify right)
			)
		)
		(property "License" "Apache-2.0"
			(at 162.56 38.1 0)
			(effects
				(font
					(size 1.27 1.27)
					(thickness 0.15)
				)
				(justify left bottom)
				(hide yes)
			)
		)
		(property "Author" "Antmicro"
			(at 165.1 38.1 0)
			(effects
				(font
					(size 1.27 1.27)
					(thickness 0.15)
				)
				(justify left bottom)
				(hide yes)
			)
		)
		(property "Voltage" ""
			(at 167.64 38.1 0)
			(effects
				(font
					(size 1.27 1.27)
				)
				(justify left bottom)
				(hide yes)
			)
		)
		(property "Dielectric" ""
			(at 170.18 38.1 0)
			(effects
				(font
					(size 1.27 1.27)
				)
				(justify left bottom)
				(hide yes)
			)
		)
		(pin "1"
		)
		(pin "2"
		)
		(instances
			(project "artix-dc-scm"
				(path ""
					(reference "C50")
					(unit 1)
				)
			)
		)
	)
	(symbol
		(lib_id "antmicroCapacitors0402:C_470n_0402")
		(at 147.32 58.42 90)
		(unit 1)
		(exclude_from_sim no)
		(in_bom yes)
		(on_board yes)
		(dnp no)
		(property "Reference" "C52"
			(at 147.955 53.975 90)
			(effects
				(font
					(size 1.27 1.27)
				)
				(justify right)
			)
		)
		(property "Value" "C_470n_0402"
			(at 157.48 38.1 0)
			(effects
				(font
					(size 1.27 1.27)
					(thickness 0.15)
				)
				(justify left bottom)
				(hide yes)
			)
		)
		(property "Footprint" "antmicro-footprints:C_0402_1005Metric"
			(at 160.02 38.1 0)
			(effects
				(font
					(size 1.27 1.27)
					(thickness 0.15)
				)
				(justify left bottom)
				(hide yes)
			)
		)
		(property "Datasheet" "https://product.tdk.com/en/search/capacitor/ceramic/mlcc/info?part_no=C1005X5R1E474M050BB"
			(at 162.56 38.1 0)
			(effects
				(font
					(size 1.27 1.27)
					(thickness 0.15)
				)
				(justify left bottom)
				(hide yes)
			)
		)
		(property "Description" "SMD Multilayer Ceramic Capacitor, 0.47 µF, 25 V, 0402 [1005 Metric], ± 20%, X5R, C"
			(at 147.32 58.42 0)
			(effects
				(font
					(size 1.27 1.27)
				)
				(hide yes)
			)
		)
		(property "Manufacturer" "TDK"
			(at 167.64 38.1 0)
			(effects
				(font
					(size 1.27 1.27)
					(thickness 0.15)
				)
				(justify left bottom)
				(hide yes)
			)
		)
		(property "MPN" "C1005X5R1E474M050BB"
			(at 165.1 38.1 0)
			(effects
				(font
					(size 1.27 1.27)
					(thickness 0.15)
				)
				(justify left bottom)
				(hide yes)
			)
		)
		(property "Val" "470n"
			(at 147.955 57.785 90)
			(effects
				(font
					(size 1.27 1.27)
					(thickness 0.15)
				)
				(justify right)
			)
		)
		(property "License" "Apache-2.0"
			(at 170.18 38.1 0)
			(effects
				(font
					(size 1.27 1.27)
					(thickness 0.15)
				)
				(justify left bottom)
				(hide yes)
			)
		)
		(property "Author" "Antmicro"
			(at 172.72 38.1 0)
			(effects
				(font
					(size 1.27 1.27)
					(thickness 0.15)
				)
				(justify left bottom)
				(hide yes)
			)
		)
		(property "Voltage" ""
			(at 175.26 38.1 0)
			(effects
				(font
					(size 1.27 1.27)
				)
				(justify left bottom)
				(hide yes)
			)
		)
		(property "Dielectric" ""
			(at 177.8 38.1 0)
			(effects
				(font
					(size 1.27 1.27)
				)
				(justify left bottom)
				(hide yes)
			)
		)
		(pin "1"
		)
		(pin "2"
		)
		(instances
			(project "artix-dc-scm"
				(path ""
					(reference "C52")
					(unit 1)
				)
			)
		)
	)
	(symbol
		(lib_id "antmicroCapacitors0402:C_470n_0402")
		(at 154.94 58.42 90)
		(unit 1)
		(exclude_from_sim no)
		(in_bom yes)
		(on_board yes)
		(dnp no)
		(property "Reference" "C54"
			(at 155.575 53.975 90)
			(effects
				(font
					(size 1.27 1.27)
				)
				(justify right)
			)
		)
		(property "Value" "C_470n_0402"
			(at 165.1 38.1 0)
			(effects
				(font
					(size 1.27 1.27)
					(thickness 0.15)
				)
				(justify left bottom)
				(hide yes)
			)
		)
		(property "Footprint" "antmicro-footprints:C_0402_1005Metric"
			(at 167.64 38.1 0)
			(effects
				(font
					(size 1.27 1.27)
					(thickness 0.15)
				)
				(justify left bottom)
				(hide yes)
			)
		)
		(property "Datasheet" "https://product.tdk.com/en/search/capacitor/ceramic/mlcc/info?part_no=C1005X5R1E474M050BB"
			(at 170.18 38.1 0)
			(effects
				(font
					(size 1.27 1.27)
					(thickness 0.15)
				)
				(justify left bottom)
				(hide yes)
			)
		)
		(property "Description" "SMD Multilayer Ceramic Capacitor, 0.47 µF, 25 V, 0402 [1005 Metric], ± 20%, X5R, C"
			(at 154.94 58.42 0)
			(effects
				(font
					(size 1.27 1.27)
				)
				(hide yes)
			)
		)
		(property "Manufacturer" "TDK"
			(at 175.26 38.1 0)
			(effects
				(font
					(size 1.27 1.27)
					(thickness 0.15)
				)
				(justify left bottom)
				(hide yes)
			)
		)
		(property "MPN" "C1005X5R1E474M050BB"
			(at 172.72 38.1 0)
			(effects
				(font
					(size 1.27 1.27)
					(thickness 0.15)
				)
				(justify left bottom)
				(hide yes)
			)
		)
		(property "Val" "470n"
			(at 155.575 57.785 90)
			(effects
				(font
					(size 1.27 1.27)
					(thickness 0.15)
				)
				(justify right)
			)
		)
		(property "License" "Apache-2.0"
			(at 177.8 38.1 0)
			(effects
				(font
					(size 1.27 1.27)
					(thickness 0.15)
				)
				(justify left bottom)
				(hide yes)
			)
		)
		(property "Author" "Antmicro"
			(at 180.34 38.1 0)
			(effects
				(font
					(size 1.27 1.27)
					(thickness 0.15)
				)
				(justify left bottom)
				(hide yes)
			)
		)
		(property "Voltage" ""
			(at 182.88 38.1 0)
			(effects
				(font
					(size 1.27 1.27)
				)
				(justify left bottom)
				(hide yes)
			)
		)
		(property "Dielectric" ""
			(at 185.42 38.1 0)
			(effects
				(font
					(size 1.27 1.27)
				)
				(justify left bottom)
				(hide yes)
			)
		)
		(pin "1"
		)
		(pin "2"
		)
		(instances
			(project "artix-dc-scm"
				(path ""
					(reference "C54")
					(unit 1)
				)
			)
		)
	)
	(symbol
		(lib_id "antmicroCapacitors0402:C_470n_0402")
		(at 162.56 58.42 90)
		(unit 1)
		(exclude_from_sim no)
		(in_bom yes)
		(on_board yes)
		(dnp no)
		(property "Reference" "C56"
			(at 163.195 53.975 90)
			(effects
				(font
					(size 1.27 1.27)
				)
				(justify right)
			)
		)
		(property "Value" "C_470n_0402"
			(at 172.72 38.1 0)
			(effects
				(font
					(size 1.27 1.27)
					(thickness 0.15)
				)
				(justify left bottom)
				(hide yes)
			)
		)
		(property "Footprint" "antmicro-footprints:C_0402_1005Metric"
			(at 175.26 38.1 0)
			(effects
				(font
					(size 1.27 1.27)
					(thickness 0.15)
				)
				(justify left bottom)
				(hide yes)
			)
		)
		(property "Datasheet" "https://product.tdk.com/en/search/capacitor/ceramic/mlcc/info?part_no=C1005X5R1E474M050BB"
			(at 177.8 38.1 0)
			(effects
				(font
					(size 1.27 1.27)
					(thickness 0.15)
				)
				(justify left bottom)
				(hide yes)
			)
		)
		(property "Description" "SMD Multilayer Ceramic Capacitor, 0.47 µF, 25 V, 0402 [1005 Metric], ± 20%, X5R, C"
			(at 162.56 58.42 0)
			(effects
				(font
					(size 1.27 1.27)
				)
				(hide yes)
			)
		)
		(property "Manufacturer" "TDK"
			(at 182.88 38.1 0)
			(effects
				(font
					(size 1.27 1.27)
					(thickness 0.15)
				)
				(justify left bottom)
				(hide yes)
			)
		)
		(property "MPN" "C1005X5R1E474M050BB"
			(at 180.34 38.1 0)
			(effects
				(font
					(size 1.27 1.27)
					(thickness 0.15)
				)
				(justify left bottom)
				(hide yes)
			)
		)
		(property "Val" "470n"
			(at 163.195 57.785 90)
			(effects
				(font
					(size 1.27 1.27)
					(thickness 0.15)
				)
				(justify right)
			)
		)
		(property "License" "Apache-2.0"
			(at 185.42 38.1 0)
			(effects
				(font
					(size 1.27 1.27)
					(thickness 0.15)
				)
				(justify left bottom)
				(hide yes)
			)
		)
		(property "Author" "Antmicro"
			(at 187.96 38.1 0)
			(effects
				(font
					(size 1.27 1.27)
					(thickness 0.15)
				)
				(justify left bottom)
				(hide yes)
			)
		)
		(property "Voltage" ""
			(at 190.5 38.1 0)
			(effects
				(font
					(size 1.27 1.27)
				)
				(justify left bottom)
				(hide yes)
			)
		)
		(property "Dielectric" ""
			(at 193.04 38.1 0)
			(effects
				(font
					(size 1.27 1.27)
				)
				(justify left bottom)
				(hide yes)
			)
		)
		(pin "1"
		)
		(pin "2"
		)
		(instances
			(project "artix-dc-scm"
				(path ""
					(reference "C56")
					(unit 1)
				)
			)
		)
	)
	(symbol
		(lib_id "antmicroCapacitors0402:C_470n_0402")
		(at 170.18 58.42 90)
		(unit 1)
		(exclude_from_sim no)
		(in_bom yes)
		(on_board yes)
		(dnp no)
		(property "Reference" "C59"
			(at 170.815 53.975 90)
			(effects
				(font
					(size 1.27 1.27)
				)
				(justify right)
			)
		)
		(property "Value" "C_470n_0402"
			(at 180.34 38.1 0)
			(effects
				(font
					(size 1.27 1.27)
					(thickness 0.15)
				)
				(justify left bottom)
				(hide yes)
			)
		)
		(property "Footprint" "antmicro-footprints:C_0402_1005Metric"
			(at 182.88 38.1 0)
			(effects
				(font
					(size 1.27 1.27)
					(thickness 0.15)
				)
				(justify left bottom)
				(hide yes)
			)
		)
		(property "Datasheet" "https://product.tdk.com/en/search/capacitor/ceramic/mlcc/info?part_no=C1005X5R1E474M050BB"
			(at 185.42 38.1 0)
			(effects
				(font
					(size 1.27 1.27)
					(thickness 0.15)
				)
				(justify left bottom)
				(hide yes)
			)
		)
		(property "Description" "SMD Multilayer Ceramic Capacitor, 0.47 µF, 25 V, 0402 [1005 Metric], ± 20%, X5R, C"
			(at 170.18 58.42 0)
			(effects
				(font
					(size 1.27 1.27)
				)
				(hide yes)
			)
		)
		(property "Manufacturer" "TDK"
			(at 190.5 38.1 0)
			(effects
				(font
					(size 1.27 1.27)
					(thickness 0.15)
				)
				(justify left bottom)
				(hide yes)
			)
		)
		(property "MPN" "C1005X5R1E474M050BB"
			(at 187.96 38.1 0)
			(effects
				(font
					(size 1.27 1.27)
					(thickness 0.15)
				)
				(justify left bottom)
				(hide yes)
			)
		)
		(property "Val" "470n"
			(at 170.815 57.785 90)
			(effects
				(font
					(size 1.27 1.27)
					(thickness 0.15)
				)
				(justify right)
			)
		)
		(property "License" "Apache-2.0"
			(at 193.04 38.1 0)
			(effects
				(font
					(size 1.27 1.27)
					(thickness 0.15)
				)
				(justify left bottom)
				(hide yes)
			)
		)
		(property "Author" "Antmicro"
			(at 195.58 38.1 0)
			(effects
				(font
					(size 1.27 1.27)
					(thickness 0.15)
				)
				(justify left bottom)
				(hide yes)
			)
		)
		(property "Voltage" ""
			(at 198.12 38.1 0)
			(effects
				(font
					(size 1.27 1.27)
				)
				(justify left bottom)
				(hide yes)
			)
		)
		(property "Dielectric" ""
			(at 200.66 38.1 0)
			(effects
				(font
					(size 1.27 1.27)
				)
				(justify left bottom)
				(hide yes)
			)
		)
		(pin "1"
		)
		(pin "2"
		)
		(instances
			(project "artix-dc-scm"
				(path ""
					(reference "C59")
					(unit 1)
				)
			)
		)
	)
	(symbol
		(lib_id "antmicroCapacitors0402:C_470n_0402")
		(at 177.8 58.42 90)
		(unit 1)
		(exclude_from_sim no)
		(in_bom yes)
		(on_board yes)
		(dnp no)
		(property "Reference" "C61"
			(at 178.435 53.975 90)
			(effects
				(font
					(size 1.27 1.27)
				)
				(justify right)
			)
		)
		(property "Value" "C_470n_0402"
			(at 187.96 38.1 0)
			(effects
				(font
					(size 1.27 1.27)
					(thickness 0.15)
				)
				(justify left bottom)
				(hide yes)
			)
		)
		(property "Footprint" "antmicro-footprints:C_0402_1005Metric"
			(at 190.5 38.1 0)
			(effects
				(font
					(size 1.27 1.27)
					(thickness 0.15)
				)
				(justify left bottom)
				(hide yes)
			)
		)
		(property "Datasheet" "https://product.tdk.com/en/search/capacitor/ceramic/mlcc/info?part_no=C1005X5R1E474M050BB"
			(at 193.04 38.1 0)
			(effects
				(font
					(size 1.27 1.27)
					(thickness 0.15)
				)
				(justify left bottom)
				(hide yes)
			)
		)
		(property "Description" "SMD Multilayer Ceramic Capacitor, 0.47 µF, 25 V, 0402 [1005 Metric], ± 20%, X5R, C"
			(at 177.8 58.42 0)
			(effects
				(font
					(size 1.27 1.27)
				)
				(hide yes)
			)
		)
		(property "Manufacturer" "TDK"
			(at 198.12 38.1 0)
			(effects
				(font
					(size 1.27 1.27)
					(thickness 0.15)
				)
				(justify left bottom)
				(hide yes)
			)
		)
		(property "MPN" "C1005X5R1E474M050BB"
			(at 195.58 38.1 0)
			(effects
				(font
					(size 1.27 1.27)
					(thickness 0.15)
				)
				(justify left bottom)
				(hide yes)
			)
		)
		(property "Val" "470n"
			(at 178.435 57.785 90)
			(effects
				(font
					(size 1.27 1.27)
					(thickness 0.15)
				)
				(justify right)
			)
		)
		(property "License" "Apache-2.0"
			(at 200.66 38.1 0)
			(effects
				(font
					(size 1.27 1.27)
					(thickness 0.15)
				)
				(justify left bottom)
				(hide yes)
			)
		)
		(property "Author" "Antmicro"
			(at 203.2 38.1 0)
			(effects
				(font
					(size 1.27 1.27)
					(thickness 0.15)
				)
				(justify left bottom)
				(hide yes)
			)
		)
		(property "Voltage" ""
			(at 205.74 38.1 0)
			(effects
				(font
					(size 1.27 1.27)
				)
				(justify left bottom)
				(hide yes)
			)
		)
		(property "Dielectric" ""
			(at 208.28 38.1 0)
			(effects
				(font
					(size 1.27 1.27)
				)
				(justify left bottom)
				(hide yes)
			)
		)
		(pin "1"
		)
		(pin "2"
		)
		(instances
			(project "artix-dc-scm"
				(path ""
					(reference "C61")
					(unit 1)
				)
			)
		)
	)
	(symbol
		(lib_id "antmicroCapacitorsmisc:C_100n_6V3_0402")
		(at 252.73 58.42 90)
		(unit 1)
		(exclude_from_sim no)
		(in_bom yes)
		(on_board yes)
		(dnp no)
		(property "Reference" "C57"
			(at 253.365 53.975 90)
			(effects
				(font
					(size 1.27 1.27)
				)
				(justify right)
			)
		)
		(property "Value" "C_100n_6V3_0402"
			(at 262.89 38.1 0)
			(effects
				(font
					(size 1.27 1.27)
					(thickness 0.15)
				)
				(justify left bottom)
				(hide yes)
			)
		)
		(property "Footprint" "antmicro-footprints:C_0402_1005Metric"
			(at 265.43 38.1 0)
			(effects
				(font
					(size 1.27 1.27)
					(thickness 0.15)
				)
				(justify left bottom)
				(hide yes)
			)
		)
		(property "Datasheet" "https://www.passivecomponent.com/wp-content/uploads/datasheet/WTC_MLCC_General_Purpose.pdf"
			(at 267.97 38.1 0)
			(effects
				(font
					(size 1.27 1.27)
					(thickness 0.15)
				)
				(justify left bottom)
				(hide yes)
			)
		)
		(property "Description" "SMT Multilayer Ceramic Capacitor, 0.1 µF, 6.3 V, 0402 [1005 Metric], ± 10%, X5R, Walsin MLCC"
			(at 252.73 58.42 0)
			(effects
				(font
					(size 1.27 1.27)
				)
				(hide yes)
			)
		)
		(property "Manufacturer" "Walsin"
			(at 273.05 38.1 0)
			(effects
				(font
					(size 1.27 1.27)
					(thickness 0.15)
				)
				(justify left bottom)
				(hide yes)
			)
		)
		(property "MPN" "0402X104K6R3CT"
			(at 270.51 38.1 0)
			(effects
				(font
					(size 1.27 1.27)
					(thickness 0.15)
				)
				(justify left bottom)
				(hide yes)
			)
		)
		(property "Val" "100n"
			(at 253.365 57.785 90)
			(effects
				(font
					(size 1.27 1.27)
					(thickness 0.15)
				)
				(justify right)
			)
		)
		(property "License" "Apache-2.0"
			(at 275.59 38.1 0)
			(effects
				(font
					(size 1.27 1.27)
					(thickness 0.15)
				)
				(justify left bottom)
				(hide yes)
			)
		)
		(property "Author" "Antmicro"
			(at 278.13 38.1 0)
			(effects
				(font
					(size 1.27 1.27)
					(thickness 0.15)
				)
				(justify left bottom)
				(hide yes)
			)
		)
		(property "Voltage" ""
			(at 280.67 38.1 0)
			(effects
				(font
					(size 1.27 1.27)
				)
				(justify left bottom)
				(hide yes)
			)
		)
		(property "Dielectric" ""
			(at 283.21 38.1 0)
			(effects
				(font
					(size 1.27 1.27)
				)
				(justify left bottom)
				(hide yes)
			)
		)
		(property "Public" "False"
			(at 285.75 38.1 0)
			(effects
				(font
					(size 1.27 1.27)
				)
				(justify left bottom)
				(hide yes)
			)
		)
		(pin "1"
		)
		(pin "2"
		)
		(instances
			(project "artix-dc-scm"
				(path ""
					(reference "C57")
					(unit 1)
				)
			)
		)
	)
	(symbol
		(lib_id "antmicroCapacitorsmisc:C_100n_6V3_0402")
		(at 243.84 58.42 90)
		(unit 1)
		(exclude_from_sim no)
		(in_bom yes)
		(on_board yes)
		(dnp no)
		(property "Reference" "C62"
			(at 244.475 53.975 90)
			(effects
				(font
					(size 1.27 1.27)
				)
				(justify right)
			)
		)
		(property "Value" "C_100n_6V3_0402"
			(at 254 38.1 0)
			(effects
				(font
					(size 1.27 1.27)
					(thickness 0.15)
				)
				(justify left bottom)
				(hide yes)
			)
		)
		(property "Footprint" "antmicro-footprints:C_0402_1005Metric"
			(at 256.54 38.1 0)
			(effects
				(font
					(size 1.27 1.27)
					(thickness 0.15)
				)
				(justify left bottom)
				(hide yes)
			)
		)
		(property "Datasheet" "https://www.passivecomponent.com/wp-content/uploads/datasheet/WTC_MLCC_General_Purpose.pdf"
			(at 259.08 38.1 0)
			(effects
				(font
					(size 1.27 1.27)
					(thickness 0.15)
				)
				(justify left bottom)
				(hide yes)
			)
		)
		(property "Description" "SMT Multilayer Ceramic Capacitor, 0.1 µF, 6.3 V, 0402 [1005 Metric], ± 10%, X5R, Walsin MLCC"
			(at 243.84 58.42 0)
			(effects
				(font
					(size 1.27 1.27)
				)
				(hide yes)
			)
		)
		(property "Manufacturer" "Walsin"
			(at 264.16 38.1 0)
			(effects
				(font
					(size 1.27 1.27)
					(thickness 0.15)
				)
				(justify left bottom)
				(hide yes)
			)
		)
		(property "MPN" "0402X104K6R3CT"
			(at 261.62 38.1 0)
			(effects
				(font
					(size 1.27 1.27)
					(thickness 0.15)
				)
				(justify left bottom)
				(hide yes)
			)
		)
		(property "Val" "100n"
			(at 244.475 57.785 90)
			(effects
				(font
					(size 1.27 1.27)
					(thickness 0.15)
				)
				(justify right)
			)
		)
		(property "License" "Apache-2.0"
			(at 266.7 38.1 0)
			(effects
				(font
					(size 1.27 1.27)
					(thickness 0.15)
				)
				(justify left bottom)
				(hide yes)
			)
		)
		(property "Author" "Antmicro"
			(at 269.24 38.1 0)
			(effects
				(font
					(size 1.27 1.27)
					(thickness 0.15)
				)
				(justify left bottom)
				(hide yes)
			)
		)
		(property "Voltage" ""
			(at 271.78 38.1 0)
			(effects
				(font
					(size 1.27 1.27)
				)
				(justify left bottom)
				(hide yes)
			)
		)
		(property "Dielectric" ""
			(at 274.32 38.1 0)
			(effects
				(font
					(size 1.27 1.27)
				)
				(justify left bottom)
				(hide yes)
			)
		)
		(property "Public" "False"
			(at 276.86 38.1 0)
			(effects
				(font
					(size 1.27 1.27)
				)
				(justify left bottom)
				(hide yes)
			)
		)
		(pin "1"
		)
		(pin "2"
		)
		(instances
			(project "artix-dc-scm"
				(path ""
					(reference "C62")
					(unit 1)
				)
			)
		)
	)
	(symbol
		(lib_id "antmicroResistors0402:R_240R_0402")
		(at 238.76 137.16 90)
		(mirror x)
		(unit 1)
		(exclude_from_sim no)
		(in_bom yes)
		(on_board yes)
		(dnp no)
		(fields_autoplaced yes)
		(property "Reference" "R60"
			(at 241.3 138.4299 90)
			(effects
				(font
					(size 1.27 1.27)
				)
				(justify right)
			)
		)
		(property "Value" "R_240R_0402"
			(at 251.46 157.48 0)
			(effects
				(font
					(size 1.27 1.27)
					(thickness 0.15)
				)
				(justify left bottom)
				(hide yes)
			)
		)
		(property "Footprint" "antmicro-footprints:R_0402_1005Metric"
			(at 254 157.48 0)
			(effects
				(font
					(size 1.27 1.27)
					(thickness 0.15)
				)
				(justify left bottom)
				(hide yes)
			)
		)
		(property "Datasheet" "https://www.bourns.com/docs/product-datasheets/cr.pdf"
			(at 256.54 157.48 0)
			(effects
				(font
					(size 1.27 1.27)
					(thickness 0.15)
				)
				(justify left bottom)
				(hide yes)
			)
		)
		(property "Description" "SMD Chip Resistor, 240 ohm, ± 1%, 63 mW, 0402 [1005 Metric], Thick Film, General Purpose"
			(at 238.76 137.16 0)
			(effects
				(font
					(size 1.27 1.27)
				)
				(hide yes)
			)
		)
		(property "Manufacturer" "Bourns"
			(at 261.62 157.48 0)
			(effects
				(font
					(size 1.27 1.27)
					(thickness 0.15)
				)
				(justify left bottom)
				(hide yes)
			)
		)
		(property "MPN" "CR0402-FX-2400GLF"
			(at 259.08 157.48 0)
			(effects
				(font
					(size 1.27 1.27)
					(thickness 0.15)
				)
				(justify left bottom)
				(hide yes)
			)
		)
		(property "Val" "240R"
			(at 241.3 140.9699 90)
			(effects
				(font
					(size 1.27 1.27)
					(thickness 0.15)
				)
				(justify right)
			)
		)
		(property "License" "Apache-2.0"
			(at 264.16 157.48 0)
			(effects
				(font
					(size 1.27 1.27)
					(thickness 0.15)
				)
				(justify left bottom)
				(hide yes)
			)
		)
		(property "Author" "Antmicro"
			(at 266.7 157.48 0)
			(effects
				(font
					(size 1.27 1.27)
					(thickness 0.15)
				)
				(justify left bottom)
				(hide yes)
			)
		)
		(property "Tolerance" "1%"
			(at 248.92 157.48 0)
			(effects
				(font
					(size 1.27 1.27)
				)
				(justify left bottom)
				(hide yes)
			)
		)
		(pin "1"
		)
		(pin "2"
		)
		(instances
			(project "artix-dc-scm"
				(path ""
					(reference "R60")
					(unit 1)
				)
			)
		)
	)
	(symbol
		(lib_id "antmicroCapacitors0402:C_10u_0402")
		(at 177.8 201.93 90)
		(unit 1)
		(exclude_from_sim no)
		(in_bom yes)
		(on_board yes)
		(dnp no)
		(property "Reference" "C40"
			(at 178.435 197.485 90)
			(effects
				(font
					(size 1.27 1.27)
				)
				(justify right)
			)
		)
		(property "Value" "C_10u_0402"
			(at 187.96 181.61 0)
			(effects
				(font
					(size 1.27 1.27)
					(thickness 0.15)
				)
				(justify left bottom)
				(hide yes)
			)
		)
		(property "Footprint" "antmicro-footprints:C_0402_1005Metric"
			(at 190.5 181.61 0)
			(effects
				(font
					(size 1.27 1.27)
					(thickness 0.15)
				)
				(justify left bottom)
				(hide yes)
			)
		)
		(property "Datasheet" "https://www.yageo.com/en/Chart/Download/pdf/CC0402MRX5R5BB106"
			(at 193.04 181.61 0)
			(effects
				(font
					(size 1.27 1.27)
					(thickness 0.15)
				)
				(justify left bottom)
				(hide yes)
			)
		)
		(property "Description" "SMD Multilayer Ceramic Capacitor, 10 µF, 6.3 V, 0402 [1005 Metric], ± 20%, X5R, CC Series"
			(at 177.8 201.93 0)
			(effects
				(font
					(size 1.27 1.27)
				)
				(hide yes)
			)
		)
		(property "Manufacturer" "YAGEO"
			(at 198.12 181.61 0)
			(effects
				(font
					(size 1.27 1.27)
					(thickness 0.15)
				)
				(justify left bottom)
				(hide yes)
			)
		)
		(property "MPN" "CC0402MRX5R5BB106"
			(at 195.58 181.61 0)
			(effects
				(font
					(size 1.27 1.27)
					(thickness 0.15)
				)
				(justify left bottom)
				(hide yes)
			)
		)
		(property "Val" "10u"
			(at 178.435 201.295 90)
			(effects
				(font
					(size 1.27 1.27)
					(thickness 0.15)
				)
				(justify right)
			)
		)
		(property "License" "Apache-2.0"
			(at 200.66 181.61 0)
			(effects
				(font
					(size 1.27 1.27)
					(thickness 0.15)
				)
				(justify left bottom)
				(hide yes)
			)
		)
		(property "Author" "Antmicro"
			(at 203.2 181.61 0)
			(effects
				(font
					(size 1.27 1.27)
					(thickness 0.15)
				)
				(justify left bottom)
				(hide yes)
			)
		)
		(property "Voltage" ""
			(at 205.74 181.61 0)
			(effects
				(font
					(size 1.27 1.27)
				)
				(justify left bottom)
				(hide yes)
			)
		)
		(property "Dielectric" ""
			(at 208.28 181.61 0)
			(effects
				(font
					(size 1.27 1.27)
				)
				(justify left bottom)
				(hide yes)
			)
		)
		(pin "1"
		)
		(pin "2"
		)
		(instances
			(project "artix-dc-scm"
				(path ""
					(reference "C40")
					(unit 1)
				)
			)
		)
	)
	(symbol
		(lib_id "antmicroResistors0402:R_10k_0402")
		(at 105.41 210.82 270)
		(mirror x)
		(unit 1)
		(exclude_from_sim no)
		(in_bom yes)
		(on_board yes)
		(dnp no)
		(property "Reference" "R57"
			(at 106.68 207.01 90)
			(effects
				(font
					(size 1.27 1.27)
				)
				(justify left)
			)
		)
		(property "Value" "R_10k_0402"
			(at 92.71 190.5 0)
			(effects
				(font
					(size 1.27 1.27)
					(thickness 0.15)
				)
				(justify left bottom)
				(hide yes)
			)
		)
		(property "Footprint" "antmicro-footprints:R_0402_1005Metric"
			(at 90.17 190.5 0)
			(effects
				(font
					(size 1.27 1.27)
					(thickness 0.15)
				)
				(justify left bottom)
				(hide yes)
			)
		)
		(property "Datasheet" "https://www.bourns.com/docs/product-datasheets/cr.pdf"
			(at 87.63 190.5 0)
			(effects
				(font
					(size 1.27 1.27)
					(thickness 0.15)
				)
				(justify left bottom)
				(hide yes)
			)
		)
		(property "Description" "SMD Chip Resistor, 10 kohm, ± 1%, 62.5 mW, 0402 [1005 Metric], Thick Film, General Purpose"
			(at 105.41 210.82 0)
			(effects
				(font
					(size 1.27 1.27)
				)
				(hide yes)
			)
		)
		(property "Manufacturer" "Bourns"
			(at 82.55 190.5 0)
			(effects
				(font
					(size 1.27 1.27)
					(thickness 0.15)
				)
				(justify left bottom)
				(hide yes)
			)
		)
		(property "MPN" "CR0402-FX-1002GLF"
			(at 85.09 190.5 0)
			(effects
				(font
					(size 1.27 1.27)
					(thickness 0.15)
				)
				(justify left bottom)
				(hide yes)
			)
		)
		(property "Val" "10k"
			(at 106.68 209.55 90)
			(effects
				(font
					(size 1.27 1.27)
					(thickness 0.15)
				)
				(justify left)
			)
		)
		(property "License" "Apache-2.0"
			(at 80.01 190.5 0)
			(effects
				(font
					(size 1.27 1.27)
					(thickness 0.15)
				)
				(justify left bottom)
				(hide yes)
			)
		)
		(property "Author" "Antmicro"
			(at 77.47 190.5 0)
			(effects
				(font
					(size 1.27 1.27)
					(thickness 0.15)
				)
				(justify left bottom)
				(hide yes)
			)
		)
		(property "Tolerance" "1%"
			(at 95.25 190.5 0)
			(effects
				(font
					(size 1.27 1.27)
				)
				(justify left bottom)
				(hide yes)
			)
		)
		(pin "1"
		)
		(pin "2"
		)
		(instances
			(project "artix-dc-scm"
				(path ""
					(reference "R57")
					(unit 1)
				)
			)
		)
	)
	(symbol
		(lib_id "antmicroCapacitors0402:C_10u_0402")
		(at 170.18 201.93 90)
		(unit 1)
		(exclude_from_sim no)
		(in_bom yes)
		(on_board yes)
		(dnp no)
		(property "Reference" "C41"
			(at 170.815 197.485 90)
			(effects
				(font
					(size 1.27 1.27)
				)
				(justify right)
			)
		)
		(property "Value" "C_10u_0402"
			(at 180.34 181.61 0)
			(effects
				(font
					(size 1.27 1.27)
					(thickness 0.15)
				)
				(justify left bottom)
				(hide yes)
			)
		)
		(property "Footprint" "antmicro-footprints:C_0402_1005Metric"
			(at 182.88 181.61 0)
			(effects
				(font
					(size 1.27 1.27)
					(thickness 0.15)
				)
				(justify left bottom)
				(hide yes)
			)
		)
		(property "Datasheet" "https://www.yageo.com/en/Chart/Download/pdf/CC0402MRX5R5BB106"
			(at 185.42 181.61 0)
			(effects
				(font
					(size 1.27 1.27)
					(thickness 0.15)
				)
				(justify left bottom)
				(hide yes)
			)
		)
		(property "Description" "SMD Multilayer Ceramic Capacitor, 10 µF, 6.3 V, 0402 [1005 Metric], ± 20%, X5R, CC Series"
			(at 170.18 201.93 0)
			(effects
				(font
					(size 1.27 1.27)
				)
				(hide yes)
			)
		)
		(property "Manufacturer" "YAGEO"
			(at 190.5 181.61 0)
			(effects
				(font
					(size 1.27 1.27)
					(thickness 0.15)
				)
				(justify left bottom)
				(hide yes)
			)
		)
		(property "MPN" "CC0402MRX5R5BB106"
			(at 187.96 181.61 0)
			(effects
				(font
					(size 1.27 1.27)
					(thickness 0.15)
				)
				(justify left bottom)
				(hide yes)
			)
		)
		(property "Val" "10u"
			(at 170.815 201.295 90)
			(effects
				(font
					(size 1.27 1.27)
					(thickness 0.15)
				)
				(justify right)
			)
		)
		(property "License" "Apache-2.0"
			(at 193.04 181.61 0)
			(effects
				(font
					(size 1.27 1.27)
					(thickness 0.15)
				)
				(justify left bottom)
				(hide yes)
			)
		)
		(property "Author" "Antmicro"
			(at 195.58 181.61 0)
			(effects
				(font
					(size 1.27 1.27)
					(thickness 0.15)
				)
				(justify left bottom)
				(hide yes)
			)
		)
		(property "Voltage" ""
			(at 198.12 181.61 0)
			(effects
				(font
					(size 1.27 1.27)
				)
				(justify left bottom)
				(hide yes)
			)
		)
		(property "Dielectric" ""
			(at 200.66 181.61 0)
			(effects
				(font
					(size 1.27 1.27)
				)
				(justify left bottom)
				(hide yes)
			)
		)
		(pin "1"
		)
		(pin "2"
		)
		(instances
			(project "artix-dc-scm"
				(path ""
					(reference "C41")
					(unit 1)
				)
			)
		)
	)
	(symbol
		(lib_id "antmicroCapacitors0402:C_10u_0402")
		(at 162.56 201.93 270)
		(mirror x)
		(unit 1)
		(exclude_from_sim no)
		(in_bom yes)
		(on_board yes)
		(dnp no)
		(property "Reference" "C43"
			(at 163.195 197.485 90)
			(effects
				(font
					(size 1.27 1.27)
				)
				(justify left)
			)
		)
		(property "Value" "C_10u_0402"
			(at 152.4 181.61 0)
			(effects
				(font
					(size 1.27 1.27)
					(thickness 0.15)
				)
				(justify left bottom)
				(hide yes)
			)
		)
		(property "Footprint" "antmicro-footprints:C_0402_1005Metric"
			(at 149.86 181.61 0)
			(effects
				(font
					(size 1.27 1.27)
					(thickness 0.15)
				)
				(justify left bottom)
				(hide yes)
			)
		)
		(property "Datasheet" "https://www.yageo.com/en/Chart/Download/pdf/CC0402MRX5R5BB106"
			(at 147.32 181.61 0)
			(effects
				(font
					(size 1.27 1.27)
					(thickness 0.15)
				)
				(justify left bottom)
				(hide yes)
			)
		)
		(property "Description" "SMD Multilayer Ceramic Capacitor, 10 µF, 6.3 V, 0402 [1005 Metric], ± 20%, X5R, CC Series"
			(at 162.56 201.93 0)
			(effects
				(font
					(size 1.27 1.27)
				)
				(hide yes)
			)
		)
		(property "Manufacturer" "YAGEO"
			(at 142.24 181.61 0)
			(effects
				(font
					(size 1.27 1.27)
					(thickness 0.15)
				)
				(justify left bottom)
				(hide yes)
			)
		)
		(property "MPN" "CC0402MRX5R5BB106"
			(at 144.78 181.61 0)
			(effects
				(font
					(size 1.27 1.27)
					(thickness 0.15)
				)
				(justify left bottom)
				(hide yes)
			)
		)
		(property "Val" "10u"
			(at 163.195 201.295 90)
			(effects
				(font
					(size 1.27 1.27)
					(thickness 0.15)
				)
				(justify left)
			)
		)
		(property "License" "Apache-2.0"
			(at 139.7 181.61 0)
			(effects
				(font
					(size 1.27 1.27)
					(thickness 0.15)
				)
				(justify left bottom)
				(hide yes)
			)
		)
		(property "Author" "Antmicro"
			(at 137.16 181.61 0)
			(effects
				(font
					(size 1.27 1.27)
					(thickness 0.15)
				)
				(justify left bottom)
				(hide yes)
			)
		)
		(property "Voltage" ""
			(at 134.62 181.61 0)
			(effects
				(font
					(size 1.27 1.27)
				)
				(justify left bottom)
				(hide yes)
			)
		)
		(property "Dielectric" ""
			(at 132.08 181.61 0)
			(effects
				(font
					(size 1.27 1.27)
				)
				(justify left bottom)
				(hide yes)
			)
		)
		(pin "1"
		)
		(pin "2"
		)
		(instances
			(project "artix-dc-scm"
				(path ""
					(reference "C43")
					(unit 1)
				)
			)
		)
	)
	(symbol
		(lib_id "antmicroResistors0402:R_51R_0402")
		(at 233.68 195.58 0)
		(mirror y)
		(unit 1)
		(exclude_from_sim no)
		(in_bom no)
		(on_board yes)
		(dnp yes)
		(property "Reference" "R54"
			(at 226.695 194.31 0)
			(effects
				(font
					(size 1.27 1.27)
				)
			)
		)
		(property "Value" "R_51R_0402"
			(at 213.36 208.28 0)
			(effects
				(font
					(size 1.27 1.27)
					(thickness 0.15)
				)
				(justify left bottom)
				(hide yes)
			)
		)
		(property "Footprint" "antmicro-footprints:R_0402_1005Metric"
			(at 213.36 210.82 0)
			(effects
				(font
					(size 1.27 1.27)
					(thickness 0.15)
				)
				(justify left bottom)
				(hide yes)
			)
		)
		(property "Datasheet" "https://www.bourns.com/docs/product-datasheets/cr.pdf"
			(at 213.36 213.36 0)
			(effects
				(font
					(size 1.27 1.27)
					(thickness 0.15)
				)
				(justify left bottom)
				(hide yes)
			)
		)
		(property "Description" "SMD Chip Resistor, 51 ohm, ± 1%, 63 mW, 0402 [1005 Metric], Thick Film, General Purpose"
			(at 233.68 195.58 0)
			(effects
				(font
					(size 1.27 1.27)
				)
				(hide yes)
			)
		)
		(property "Manufacturer" "Bourns"
			(at 213.36 218.44 0)
			(effects
				(font
					(size 1.27 1.27)
					(thickness 0.15)
				)
				(justify left bottom)
				(hide yes)
			)
		)
		(property "MPN" "CR0402-FX-51R0GLF"
			(at 213.36 215.9 0)
			(effects
				(font
					(size 1.27 1.27)
					(thickness 0.15)
				)
				(justify left bottom)
				(hide yes)
			)
		)
		(property "Val" "51R"
			(at 237.49 195.58 0)
			(effects
				(font
					(size 1.27 1.27)
					(thickness 0.15)
				)
				(justify left bottom)
			)
		)
		(property "License" "Apache-2.0"
			(at 213.36 220.98 0)
			(effects
				(font
					(size 1.27 1.27)
					(thickness 0.15)
				)
				(justify left bottom)
				(hide yes)
			)
		)
		(property "Author" "Antmicro"
			(at 213.36 223.52 0)
			(effects
				(font
					(size 1.27 1.27)
					(thickness 0.15)
				)
				(justify left bottom)
				(hide yes)
			)
		)
		(property "Tolerance" "1%"
			(at 213.36 205.74 0)
			(effects
				(font
					(size 1.27 1.27)
				)
				(justify left bottom)
				(hide yes)
			)
		)
		(pin "1"
		)
		(pin "2"
		)
		(instances
			(project "artix-dc-scm"
				(path ""
					(reference "R54")
					(unit 1)
				)
			)
		)
	)
	(symbol
		(lib_id "antmicroResistors0402:R_51R_0402")
		(at 233.68 198.12 0)
		(mirror y)
		(unit 1)
		(exclude_from_sim no)
		(in_bom no)
		(on_board yes)
		(dnp yes)
		(property "Reference" "R55"
			(at 226.695 196.85 0)
			(effects
				(font
					(size 1.27 1.27)
				)
			)
		)
		(property "Value" "R_51R_0402"
			(at 213.36 210.82 0)
			(effects
				(font
					(size 1.27 1.27)
					(thickness 0.15)
				)
				(justify left bottom)
				(hide yes)
			)
		)
		(property "Footprint" "antmicro-footprints:R_0402_1005Metric"
			(at 213.36 213.36 0)
			(effects
				(font
					(size 1.27 1.27)
					(thickness 0.15)
				)
				(justify left bottom)
				(hide yes)
			)
		)
		(property "Datasheet" "https://www.bourns.com/docs/product-datasheets/cr.pdf"
			(at 213.36 215.9 0)
			(effects
				(font
					(size 1.27 1.27)
					(thickness 0.15)
				)
				(justify left bottom)
				(hide yes)
			)
		)
		(property "Description" "SMD Chip Resistor, 51 ohm, ± 1%, 63 mW, 0402 [1005 Metric], Thick Film, General Purpose"
			(at 233.68 198.12 0)
			(effects
				(font
					(size 1.27 1.27)
				)
				(hide yes)
			)
		)
		(property "Manufacturer" "Bourns"
			(at 213.36 220.98 0)
			(effects
				(font
					(size 1.27 1.27)
					(thickness 0.15)
				)
				(justify left bottom)
				(hide yes)
			)
		)
		(property "MPN" "CR0402-FX-51R0GLF"
			(at 213.36 218.44 0)
			(effects
				(font
					(size 1.27 1.27)
					(thickness 0.15)
				)
				(justify left bottom)
				(hide yes)
			)
		)
		(property "Val" "51R"
			(at 237.49 198.12 0)
			(effects
				(font
					(size 1.27 1.27)
					(thickness 0.15)
				)
				(justify left bottom)
			)
		)
		(property "License" "Apache-2.0"
			(at 213.36 223.52 0)
			(effects
				(font
					(size 1.27 1.27)
					(thickness 0.15)
				)
				(justify left bottom)
				(hide yes)
			)
		)
		(property "Author" "Antmicro"
			(at 213.36 226.06 0)
			(effects
				(font
					(size 1.27 1.27)
					(thickness 0.15)
				)
				(justify left bottom)
				(hide yes)
			)
		)
		(property "Tolerance" "1%"
			(at 213.36 208.28 0)
			(effects
				(font
					(size 1.27 1.27)
				)
				(justify left bottom)
				(hide yes)
			)
		)
		(pin "1"
		)
		(pin "2"
		)
		(instances
			(project "artix-dc-scm"
				(path ""
					(reference "R55")
					(unit 1)
				)
			)
		)
	)
	(symbol
		(lib_id "antmicroResistors0402:R_51R_0402")
		(at 233.68 200.66 0)
		(mirror y)
		(unit 1)
		(exclude_from_sim no)
		(in_bom no)
		(on_board yes)
		(dnp yes)
		(property "Reference" "R56"
			(at 226.695 199.39 0)
			(effects
				(font
					(size 1.27 1.27)
				)
			)
		)
		(property "Value" "R_51R_0402"
			(at 213.36 213.36 0)
			(effects
				(font
					(size 1.27 1.27)
					(thickness 0.15)
				)
				(justify left bottom)
				(hide yes)
			)
		)
		(property "Footprint" "antmicro-footprints:R_0402_1005Metric"
			(at 213.36 215.9 0)
			(effects
				(font
					(size 1.27 1.27)
					(thickness 0.15)
				)
				(justify left bottom)
				(hide yes)
			)
		)
		(property "Datasheet" "https://www.bourns.com/docs/product-datasheets/cr.pdf"
			(at 213.36 218.44 0)
			(effects
				(font
					(size 1.27 1.27)
					(thickness 0.15)
				)
				(justify left bottom)
				(hide yes)
			)
		)
		(property "Description" "SMD Chip Resistor, 51 ohm, ± 1%, 63 mW, 0402 [1005 Metric], Thick Film, General Purpose"
			(at 233.68 200.66 0)
			(effects
				(font
					(size 1.27 1.27)
				)
				(hide yes)
			)
		)
		(property "Manufacturer" "Bourns"
			(at 213.36 223.52 0)
			(effects
				(font
					(size 1.27 1.27)
					(thickness 0.15)
				)
				(justify left bottom)
				(hide yes)
			)
		)
		(property "MPN" "CR0402-FX-51R0GLF"
			(at 213.36 220.98 0)
			(effects
				(font
					(size 1.27 1.27)
					(thickness 0.15)
				)
				(justify left bottom)
				(hide yes)
			)
		)
		(property "Val" "51R"
			(at 237.49 200.66 0)
			(effects
				(font
					(size 1.27 1.27)
					(thickness 0.15)
				)
				(justify left bottom)
			)
		)
		(property "License" "Apache-2.0"
			(at 213.36 226.06 0)
			(effects
				(font
					(size 1.27 1.27)
					(thickness 0.15)
				)
				(justify left bottom)
				(hide yes)
			)
		)
		(property "Author" "Antmicro"
			(at 213.36 228.6 0)
			(effects
				(font
					(size 1.27 1.27)
					(thickness 0.15)
				)
				(justify left bottom)
				(hide yes)
			)
		)
		(property "Tolerance" "1%"
			(at 213.36 210.82 0)
			(effects
				(font
					(size 1.27 1.27)
				)
				(justify left bottom)
				(hide yes)
			)
		)
		(pin "1"
		)
		(pin "2"
		)
		(instances
			(project "artix-dc-scm"
				(path ""
					(reference "R56")
					(unit 1)
				)
			)
		)
	)
	(symbol
		(lib_id "antmicroResistors0402:R_51R_0402")
		(at 233.68 203.2 0)
		(mirror y)
		(unit 1)
		(exclude_from_sim no)
		(in_bom no)
		(on_board yes)
		(dnp yes)
		(property "Reference" "R162"
			(at 226.06 201.93 0)
			(effects
				(font
					(size 1.27 1.27)
				)
			)
		)
		(property "Value" "R_51R_0402"
			(at 213.36 215.9 0)
			(effects
				(font
					(size 1.27 1.27)
					(thickness 0.15)
				)
				(justify left bottom)
				(hide yes)
			)
		)
		(property "Footprint" "antmicro-footprints:R_0402_1005Metric"
			(at 213.36 218.44 0)
			(effects
				(font
					(size 1.27 1.27)
					(thickness 0.15)
				)
				(justify left bottom)
				(hide yes)
			)
		)
		(property "Datasheet" "https://www.bourns.com/docs/product-datasheets/cr.pdf"
			(at 213.36 220.98 0)
			(effects
				(font
					(size 1.27 1.27)
					(thickness 0.15)
				)
				(justify left bottom)
				(hide yes)
			)
		)
		(property "Description" "SMD Chip Resistor, 51 ohm, ± 1%, 63 mW, 0402 [1005 Metric], Thick Film, General Purpose"
			(at 233.68 203.2 0)
			(effects
				(font
					(size 1.27 1.27)
				)
				(hide yes)
			)
		)
		(property "Manufacturer" "Bourns"
			(at 213.36 226.06 0)
			(effects
				(font
					(size 1.27 1.27)
					(thickness 0.15)
				)
				(justify left bottom)
				(hide yes)
			)
		)
		(property "MPN" "CR0402-FX-51R0GLF"
			(at 213.36 223.52 0)
			(effects
				(font
					(size 1.27 1.27)
					(thickness 0.15)
				)
				(justify left bottom)
				(hide yes)
			)
		)
		(property "Val" "51R"
			(at 237.49 203.2 0)
			(effects
				(font
					(size 1.27 1.27)
					(thickness 0.15)
				)
				(justify left bottom)
			)
		)
		(property "License" "Apache-2.0"
			(at 213.36 228.6 0)
			(effects
				(font
					(size 1.27 1.27)
					(thickness 0.15)
				)
				(justify left bottom)
				(hide yes)
			)
		)
		(property "Author" "Antmicro"
			(at 213.36 231.14 0)
			(effects
				(font
					(size 1.27 1.27)
					(thickness 0.15)
				)
				(justify left bottom)
				(hide yes)
			)
		)
		(property "Tolerance" "1%"
			(at 213.36 213.36 0)
			(effects
				(font
					(size 1.27 1.27)
				)
				(justify left bottom)
				(hide yes)
			)
		)
		(pin "1"
		)
		(pin "2"
		)
		(instances
			(project "artix-dc-scm"
				(path ""
					(reference "R162")
					(unit 1)
				)
			)
		)
	)
	(symbol
		(lib_id "antmicroResistors0402:R_51R_0402")
		(at 233.68 205.74 0)
		(mirror y)
		(unit 1)
		(exclude_from_sim no)
		(in_bom no)
		(on_board yes)
		(dnp yes)
		(property "Reference" "R163"
			(at 226.06 204.47 0)
			(effects
				(font
					(size 1.27 1.27)
				)
			)
		)
		(property "Value" "R_51R_0402"
			(at 213.36 218.44 0)
			(effects
				(font
					(size 1.27 1.27)
					(thickness 0.15)
				)
				(justify left bottom)
				(hide yes)
			)
		)
		(property "Footprint" "antmicro-footprints:R_0402_1005Metric"
			(at 213.36 220.98 0)
			(effects
				(font
					(size 1.27 1.27)
					(thickness 0.15)
				)
				(justify left bottom)
				(hide yes)
			)
		)
		(property "Datasheet" "https://www.bourns.com/docs/product-datasheets/cr.pdf"
			(at 213.36 223.52 0)
			(effects
				(font
					(size 1.27 1.27)
					(thickness 0.15)
				)
				(justify left bottom)
				(hide yes)
			)
		)
		(property "Description" "SMD Chip Resistor, 51 ohm, ± 1%, 63 mW, 0402 [1005 Metric], Thick Film, General Purpose"
			(at 233.68 205.74 0)
			(effects
				(font
					(size 1.27 1.27)
				)
				(hide yes)
			)
		)
		(property "Manufacturer" "Bourns"
			(at 213.36 228.6 0)
			(effects
				(font
					(size 1.27 1.27)
					(thickness 0.15)
				)
				(justify left bottom)
				(hide yes)
			)
		)
		(property "MPN" "CR0402-FX-51R0GLF"
			(at 213.36 226.06 0)
			(effects
				(font
					(size 1.27 1.27)
					(thickness 0.15)
				)
				(justify left bottom)
				(hide yes)
			)
		)
		(property "Val" "51R"
			(at 237.49 205.74 0)
			(effects
				(font
					(size 1.27 1.27)
					(thickness 0.15)
				)
				(justify left bottom)
			)
		)
		(property "License" "Apache-2.0"
			(at 213.36 231.14 0)
			(effects
				(font
					(size 1.27 1.27)
					(thickness 0.15)
				)
				(justify left bottom)
				(hide yes)
			)
		)
		(property "Author" "Antmicro"
			(at 213.36 233.68 0)
			(effects
				(font
					(size 1.27 1.27)
					(thickness 0.15)
				)
				(justify left bottom)
				(hide yes)
			)
		)
		(property "Tolerance" "1%"
			(at 213.36 215.9 0)
			(effects
				(font
					(size 1.27 1.27)
				)
				(justify left bottom)
				(hide yes)
			)
		)
		(pin "1"
		)
		(pin "2"
		)
		(instances
			(project "artix-dc-scm"
				(path ""
					(reference "R163")
					(unit 1)
				)
			)
		)
	)
	(symbol
		(lib_id "antmicroResistors0402:R_51R_0402")
		(at 233.68 208.28 0)
		(mirror y)
		(unit 1)
		(exclude_from_sim no)
		(in_bom no)
		(on_board yes)
		(dnp yes)
		(property "Reference" "R164"
			(at 226.06 207.01 0)
			(effects
				(font
					(size 1.27 1.27)
				)
			)
		)
		(property "Value" "R_51R_0402"
			(at 213.36 220.98 0)
			(effects
				(font
					(size 1.27 1.27)
					(thickness 0.15)
				)
				(justify left bottom)
				(hide yes)
			)
		)
		(property "Footprint" "antmicro-footprints:R_0402_1005Metric"
			(at 213.36 223.52 0)
			(effects
				(font
					(size 1.27 1.27)
					(thickness 0.15)
				)
				(justify left bottom)
				(hide yes)
			)
		)
		(property "Datasheet" "https://www.bourns.com/docs/product-datasheets/cr.pdf"
			(at 213.36 226.06 0)
			(effects
				(font
					(size 1.27 1.27)
					(thickness 0.15)
				)
				(justify left bottom)
				(hide yes)
			)
		)
		(property "Description" "SMD Chip Resistor, 51 ohm, ± 1%, 63 mW, 0402 [1005 Metric], Thick Film, General Purpose"
			(at 233.68 208.28 0)
			(effects
				(font
					(size 1.27 1.27)
				)
				(hide yes)
			)
		)
		(property "Manufacturer" "Bourns"
			(at 213.36 231.14 0)
			(effects
				(font
					(size 1.27 1.27)
					(thickness 0.15)
				)
				(justify left bottom)
				(hide yes)
			)
		)
		(property "MPN" "CR0402-FX-51R0GLF"
			(at 213.36 228.6 0)
			(effects
				(font
					(size 1.27 1.27)
					(thickness 0.15)
				)
				(justify left bottom)
				(hide yes)
			)
		)
		(property "Val" "51R"
			(at 237.49 208.28 0)
			(effects
				(font
					(size 1.27 1.27)
					(thickness 0.15)
				)
				(justify left bottom)
			)
		)
		(property "License" "Apache-2.0"
			(at 213.36 233.68 0)
			(effects
				(font
					(size 1.27 1.27)
					(thickness 0.15)
				)
				(justify left bottom)
				(hide yes)
			)
		)
		(property "Author" "Antmicro"
			(at 213.36 236.22 0)
			(effects
				(font
					(size 1.27 1.27)
					(thickness 0.15)
				)
				(justify left bottom)
				(hide yes)
			)
		)
		(property "Tolerance" "1%"
			(at 213.36 218.44 0)
			(effects
				(font
					(size 1.27 1.27)
				)
				(justify left bottom)
				(hide yes)
			)
		)
		(pin "1"
		)
		(pin "2"
		)
		(instances
			(project "artix-dc-scm"
				(path ""
					(reference "R164")
					(unit 1)
				)
			)
		)
	)
	(symbol
		(lib_id "antmicroResistors0402:R_51R_0402")
		(at 233.68 210.82 0)
		(mirror y)
		(unit 1)
		(exclude_from_sim no)
		(in_bom no)
		(on_board yes)
		(dnp yes)
		(property "Reference" "R167"
			(at 226.06 209.55 0)
			(effects
				(font
					(size 1.27 1.27)
				)
			)
		)
		(property "Value" "R_51R_0402"
			(at 213.36 223.52 0)
			(effects
				(font
					(size 1.27 1.27)
					(thickness 0.15)
				)
				(justify left bottom)
				(hide yes)
			)
		)
		(property "Footprint" "antmicro-footprints:R_0402_1005Metric"
			(at 213.36 226.06 0)
			(effects
				(font
					(size 1.27 1.27)
					(thickness 0.15)
				)
				(justify left bottom)
				(hide yes)
			)
		)
		(property "Datasheet" "https://www.bourns.com/docs/product-datasheets/cr.pdf"
			(at 213.36 228.6 0)
			(effects
				(font
					(size 1.27 1.27)
					(thickness 0.15)
				)
				(justify left bottom)
				(hide yes)
			)
		)
		(property "Description" "SMD Chip Resistor, 51 ohm, ± 1%, 63 mW, 0402 [1005 Metric], Thick Film, General Purpose"
			(at 233.68 210.82 0)
			(effects
				(font
					(size 1.27 1.27)
				)
				(hide yes)
			)
		)
		(property "Manufacturer" "Bourns"
			(at 213.36 233.68 0)
			(effects
				(font
					(size 1.27 1.27)
					(thickness 0.15)
				)
				(justify left bottom)
				(hide yes)
			)
		)
		(property "MPN" "CR0402-FX-51R0GLF"
			(at 213.36 231.14 0)
			(effects
				(font
					(size 1.27 1.27)
					(thickness 0.15)
				)
				(justify left bottom)
				(hide yes)
			)
		)
		(property "Val" "51R"
			(at 237.49 210.82 0)
			(effects
				(font
					(size 1.27 1.27)
					(thickness 0.15)
				)
				(justify left bottom)
			)
		)
		(property "License" "Apache-2.0"
			(at 213.36 236.22 0)
			(effects
				(font
					(size 1.27 1.27)
					(thickness 0.15)
				)
				(justify left bottom)
				(hide yes)
			)
		)
		(property "Author" "Antmicro"
			(at 213.36 238.76 0)
			(effects
				(font
					(size 1.27 1.27)
					(thickness 0.15)
				)
				(justify left bottom)
				(hide yes)
			)
		)
		(property "Tolerance" "1%"
			(at 213.36 220.98 0)
			(effects
				(font
					(size 1.27 1.27)
				)
				(justify left bottom)
				(hide yes)
			)
		)
		(pin "1"
		)
		(pin "2"
		)
		(instances
			(project "artix-dc-scm"
				(path ""
					(reference "R167")
					(unit 1)
				)
			)
		)
	)
	(symbol
		(lib_id "antmicroResistors0402:R_51R_0402")
		(at 233.68 213.36 0)
		(mirror y)
		(unit 1)
		(exclude_from_sim no)
		(in_bom no)
		(on_board yes)
		(dnp yes)
		(property "Reference" "R168"
			(at 226.06 212.09 0)
			(effects
				(font
					(size 1.27 1.27)
				)
			)
		)
		(property "Value" "R_51R_0402"
			(at 213.36 226.06 0)
			(effects
				(font
					(size 1.27 1.27)
					(thickness 0.15)
				)
				(justify left bottom)
				(hide yes)
			)
		)
		(property "Footprint" "antmicro-footprints:R_0402_1005Metric"
			(at 213.36 228.6 0)
			(effects
				(font
					(size 1.27 1.27)
					(thickness 0.15)
				)
				(justify left bottom)
				(hide yes)
			)
		)
		(property "Datasheet" "https://www.bourns.com/docs/product-datasheets/cr.pdf"
			(at 213.36 231.14 0)
			(effects
				(font
					(size 1.27 1.27)
					(thickness 0.15)
				)
				(justify left bottom)
				(hide yes)
			)
		)
		(property "Description" "SMD Chip Resistor, 51 ohm, ± 1%, 63 mW, 0402 [1005 Metric], Thick Film, General Purpose"
			(at 233.68 213.36 0)
			(effects
				(font
					(size 1.27 1.27)
				)
				(hide yes)
			)
		)
		(property "Manufacturer" "Bourns"
			(at 213.36 236.22 0)
			(effects
				(font
					(size 1.27 1.27)
					(thickness 0.15)
				)
				(justify left bottom)
				(hide yes)
			)
		)
		(property "MPN" "CR0402-FX-51R0GLF"
			(at 213.36 233.68 0)
			(effects
				(font
					(size 1.27 1.27)
					(thickness 0.15)
				)
				(justify left bottom)
				(hide yes)
			)
		)
		(property "Val" "51R"
			(at 237.49 213.36 0)
			(effects
				(font
					(size 1.27 1.27)
					(thickness 0.15)
				)
				(justify left bottom)
			)
		)
		(property "License" "Apache-2.0"
			(at 213.36 238.76 0)
			(effects
				(font
					(size 1.27 1.27)
					(thickness 0.15)
				)
				(justify left bottom)
				(hide yes)
			)
		)
		(property "Author" "Antmicro"
			(at 213.36 241.3 0)
			(effects
				(font
					(size 1.27 1.27)
					(thickness 0.15)
				)
				(justify left bottom)
				(hide yes)
			)
		)
		(property "Tolerance" "1%"
			(at 213.36 223.52 0)
			(effects
				(font
					(size 1.27 1.27)
				)
				(justify left bottom)
				(hide yes)
			)
		)
		(pin "1"
		)
		(pin "2"
		)
		(instances
			(project "artix-dc-scm"
				(path ""
					(reference "R168")
					(unit 1)
				)
			)
		)
	)
	(symbol
		(lib_id "antmicroResistors0402:R_51R_0402")
		(at 233.68 218.44 0)
		(mirror y)
		(unit 1)
		(exclude_from_sim no)
		(in_bom no)
		(on_board yes)
		(dnp yes)
		(property "Reference" "R169"
			(at 226.06 217.17 0)
			(effects
				(font
					(size 1.27 1.27)
				)
			)
		)
		(property "Value" "R_51R_0402"
			(at 213.36 231.14 0)
			(effects
				(font
					(size 1.27 1.27)
					(thickness 0.15)
				)
				(justify left bottom)
				(hide yes)
			)
		)
		(property "Footprint" "antmicro-footprints:R_0402_1005Metric"
			(at 213.36 233.68 0)
			(effects
				(font
					(size 1.27 1.27)
					(thickness 0.15)
				)
				(justify left bottom)
				(hide yes)
			)
		)
		(property "Datasheet" "https://www.bourns.com/docs/product-datasheets/cr.pdf"
			(at 213.36 236.22 0)
			(effects
				(font
					(size 1.27 1.27)
					(thickness 0.15)
				)
				(justify left bottom)
				(hide yes)
			)
		)
		(property "Description" "SMD Chip Resistor, 51 ohm, ± 1%, 63 mW, 0402 [1005 Metric], Thick Film, General Purpose"
			(at 233.68 218.44 0)
			(effects
				(font
					(size 1.27 1.27)
				)
				(hide yes)
			)
		)
		(property "Manufacturer" "Bourns"
			(at 213.36 241.3 0)
			(effects
				(font
					(size 1.27 1.27)
					(thickness 0.15)
				)
				(justify left bottom)
				(hide yes)
			)
		)
		(property "MPN" "CR0402-FX-51R0GLF"
			(at 213.36 238.76 0)
			(effects
				(font
					(size 1.27 1.27)
					(thickness 0.15)
				)
				(justify left bottom)
				(hide yes)
			)
		)
		(property "Val" "51R"
			(at 237.49 218.44 0)
			(effects
				(font
					(size 1.27 1.27)
					(thickness 0.15)
				)
				(justify left bottom)
			)
		)
		(property "License" "Apache-2.0"
			(at 213.36 243.84 0)
			(effects
				(font
					(size 1.27 1.27)
					(thickness 0.15)
				)
				(justify left bottom)
				(hide yes)
			)
		)
		(property "Author" "Antmicro"
			(at 213.36 246.38 0)
			(effects
				(font
					(size 1.27 1.27)
					(thickness 0.15)
				)
				(justify left bottom)
				(hide yes)
			)
		)
		(property "Tolerance" "1%"
			(at 213.36 228.6 0)
			(effects
				(font
					(size 1.27 1.27)
				)
				(justify left bottom)
				(hide yes)
			)
		)
		(pin "1"
		)
		(pin "2"
		)
		(instances
			(project "artix-dc-scm"
				(path ""
					(reference "R169")
					(unit 1)
				)
			)
		)
	)
	(symbol
		(lib_id "antmicroResistors0402:R_51R_0402")
		(at 233.68 220.98 0)
		(mirror y)
		(unit 1)
		(exclude_from_sim no)
		(in_bom no)
		(on_board yes)
		(dnp yes)
		(property "Reference" "R170"
			(at 226.06 219.71 0)
			(effects
				(font
					(size 1.27 1.27)
				)
			)
		)
		(property "Value" "R_51R_0402"
			(at 213.36 233.68 0)
			(effects
				(font
					(size 1.27 1.27)
					(thickness 0.15)
				)
				(justify left bottom)
				(hide yes)
			)
		)
		(property "Footprint" "antmicro-footprints:R_0402_1005Metric"
			(at 213.36 236.22 0)
			(effects
				(font
					(size 1.27 1.27)
					(thickness 0.15)
				)
				(justify left bottom)
				(hide yes)
			)
		)
		(property "Datasheet" "https://www.bourns.com/docs/product-datasheets/cr.pdf"
			(at 213.36 238.76 0)
			(effects
				(font
					(size 1.27 1.27)
					(thickness 0.15)
				)
				(justify left bottom)
				(hide yes)
			)
		)
		(property "Description" "SMD Chip Resistor, 51 ohm, ± 1%, 63 mW, 0402 [1005 Metric], Thick Film, General Purpose"
			(at 233.68 220.98 0)
			(effects
				(font
					(size 1.27 1.27)
				)
				(hide yes)
			)
		)
		(property "Manufacturer" "Bourns"
			(at 213.36 243.84 0)
			(effects
				(font
					(size 1.27 1.27)
					(thickness 0.15)
				)
				(justify left bottom)
				(hide yes)
			)
		)
		(property "MPN" "CR0402-FX-51R0GLF"
			(at 213.36 241.3 0)
			(effects
				(font
					(size 1.27 1.27)
					(thickness 0.15)
				)
				(justify left bottom)
				(hide yes)
			)
		)
		(property "Val" "51R"
			(at 237.49 220.98 0)
			(effects
				(font
					(size 1.27 1.27)
					(thickness 0.15)
				)
				(justify left bottom)
			)
		)
		(property "License" "Apache-2.0"
			(at 213.36 246.38 0)
			(effects
				(font
					(size 1.27 1.27)
					(thickness 0.15)
				)
				(justify left bottom)
				(hide yes)
			)
		)
		(property "Author" "Antmicro"
			(at 213.36 248.92 0)
			(effects
				(font
					(size 1.27 1.27)
					(thickness 0.15)
				)
				(justify left bottom)
				(hide yes)
			)
		)
		(property "Tolerance" "1%"
			(at 213.36 231.14 0)
			(effects
				(font
					(size 1.27 1.27)
				)
				(justify left bottom)
				(hide yes)
			)
		)
		(pin "1"
		)
		(pin "2"
		)
		(instances
			(project "artix-dc-scm"
				(path ""
					(reference "R170")
					(unit 1)
				)
			)
		)
	)
	(symbol
		(lib_id "antmicroResistors0402:R_51R_0402")
		(at 233.68 223.52 0)
		(mirror y)
		(unit 1)
		(exclude_from_sim no)
		(in_bom no)
		(on_board yes)
		(dnp yes)
		(property "Reference" "R171"
			(at 226.06 222.25 0)
			(effects
				(font
					(size 1.27 1.27)
				)
			)
		)
		(property "Value" "R_51R_0402"
			(at 213.36 236.22 0)
			(effects
				(font
					(size 1.27 1.27)
					(thickness 0.15)
				)
				(justify left bottom)
				(hide yes)
			)
		)
		(property "Footprint" "antmicro-footprints:R_0402_1005Metric"
			(at 213.36 238.76 0)
			(effects
				(font
					(size 1.27 1.27)
					(thickness 0.15)
				)
				(justify left bottom)
				(hide yes)
			)
		)
		(property "Datasheet" "https://www.bourns.com/docs/product-datasheets/cr.pdf"
			(at 213.36 241.3 0)
			(effects
				(font
					(size 1.27 1.27)
					(thickness 0.15)
				)
				(justify left bottom)
				(hide yes)
			)
		)
		(property "Description" "SMD Chip Resistor, 51 ohm, ± 1%, 63 mW, 0402 [1005 Metric], Thick Film, General Purpose"
			(at 233.68 223.52 0)
			(effects
				(font
					(size 1.27 1.27)
				)
				(hide yes)
			)
		)
		(property "Manufacturer" "Bourns"
			(at 213.36 246.38 0)
			(effects
				(font
					(size 1.27 1.27)
					(thickness 0.15)
				)
				(justify left bottom)
				(hide yes)
			)
		)
		(property "MPN" "CR0402-FX-51R0GLF"
			(at 213.36 243.84 0)
			(effects
				(font
					(size 1.27 1.27)
					(thickness 0.15)
				)
				(justify left bottom)
				(hide yes)
			)
		)
		(property "Val" "51R"
			(at 237.49 223.52 0)
			(effects
				(font
					(size 1.27 1.27)
					(thickness 0.15)
				)
				(justify left bottom)
			)
		)
		(property "License" "Apache-2.0"
			(at 213.36 248.92 0)
			(effects
				(font
					(size 1.27 1.27)
					(thickness 0.15)
				)
				(justify left bottom)
				(hide yes)
			)
		)
		(property "Author" "Antmicro"
			(at 213.36 251.46 0)
			(effects
				(font
					(size 1.27 1.27)
					(thickness 0.15)
				)
				(justify left bottom)
				(hide yes)
			)
		)
		(property "Tolerance" "1%"
			(at 213.36 233.68 0)
			(effects
				(font
					(size 1.27 1.27)
				)
				(justify left bottom)
				(hide yes)
			)
		)
		(pin "1"
		)
		(pin "2"
		)
		(instances
			(project "artix-dc-scm"
				(path ""
					(reference "R171")
					(unit 1)
				)
			)
		)
	)
	(symbol
		(lib_id "antmicroResistors0402:R_51R_0402")
		(at 233.68 226.06 0)
		(mirror y)
		(unit 1)
		(exclude_from_sim no)
		(in_bom no)
		(on_board yes)
		(dnp yes)
		(property "Reference" "R172"
			(at 226.06 224.79 0)
			(effects
				(font
					(size 1.27 1.27)
				)
			)
		)
		(property "Value" "R_51R_0402"
			(at 213.36 238.76 0)
			(effects
				(font
					(size 1.27 1.27)
					(thickness 0.15)
				)
				(justify left bottom)
				(hide yes)
			)
		)
		(property "Footprint" "antmicro-footprints:R_0402_1005Metric"
			(at 213.36 241.3 0)
			(effects
				(font
					(size 1.27 1.27)
					(thickness 0.15)
				)
				(justify left bottom)
				(hide yes)
			)
		)
		(property "Datasheet" "https://www.bourns.com/docs/product-datasheets/cr.pdf"
			(at 213.36 243.84 0)
			(effects
				(font
					(size 1.27 1.27)
					(thickness 0.15)
				)
				(justify left bottom)
				(hide yes)
			)
		)
		(property "Description" "SMD Chip Resistor, 51 ohm, ± 1%, 63 mW, 0402 [1005 Metric], Thick Film, General Purpose"
			(at 233.68 226.06 0)
			(effects
				(font
					(size 1.27 1.27)
				)
				(hide yes)
			)
		)
		(property "Manufacturer" "Bourns"
			(at 213.36 248.92 0)
			(effects
				(font
					(size 1.27 1.27)
					(thickness 0.15)
				)
				(justify left bottom)
				(hide yes)
			)
		)
		(property "MPN" "CR0402-FX-51R0GLF"
			(at 213.36 246.38 0)
			(effects
				(font
					(size 1.27 1.27)
					(thickness 0.15)
				)
				(justify left bottom)
				(hide yes)
			)
		)
		(property "Val" "51R"
			(at 237.49 226.06 0)
			(effects
				(font
					(size 1.27 1.27)
					(thickness 0.15)
				)
				(justify left bottom)
			)
		)
		(property "License" "Apache-2.0"
			(at 213.36 251.46 0)
			(effects
				(font
					(size 1.27 1.27)
					(thickness 0.15)
				)
				(justify left bottom)
				(hide yes)
			)
		)
		(property "Author" "Antmicro"
			(at 213.36 254 0)
			(effects
				(font
					(size 1.27 1.27)
					(thickness 0.15)
				)
				(justify left bottom)
				(hide yes)
			)
		)
		(property "Tolerance" "1%"
			(at 213.36 236.22 0)
			(effects
				(font
					(size 1.27 1.27)
				)
				(justify left bottom)
				(hide yes)
			)
		)
		(pin "1"
		)
		(pin "2"
		)
		(instances
			(project "artix-dc-scm"
				(path ""
					(reference "R172")
					(unit 1)
				)
			)
		)
	)
	(symbol
		(lib_id "antmicroResistors0402:R_51R_0402")
		(at 233.68 228.6 0)
		(mirror y)
		(unit 1)
		(exclude_from_sim no)
		(in_bom no)
		(on_board yes)
		(dnp yes)
		(property "Reference" "R173"
			(at 226.06 227.33 0)
			(effects
				(font
					(size 1.27 1.27)
				)
			)
		)
		(property "Value" "R_51R_0402"
			(at 213.36 241.3 0)
			(effects
				(font
					(size 1.27 1.27)
					(thickness 0.15)
				)
				(justify left bottom)
				(hide yes)
			)
		)
		(property "Footprint" "antmicro-footprints:R_0402_1005Metric"
			(at 213.36 243.84 0)
			(effects
				(font
					(size 1.27 1.27)
					(thickness 0.15)
				)
				(justify left bottom)
				(hide yes)
			)
		)
		(property "Datasheet" "https://www.bourns.com/docs/product-datasheets/cr.pdf"
			(at 213.36 246.38 0)
			(effects
				(font
					(size 1.27 1.27)
					(thickness 0.15)
				)
				(justify left bottom)
				(hide yes)
			)
		)
		(property "Description" "SMD Chip Resistor, 51 ohm, ± 1%, 63 mW, 0402 [1005 Metric], Thick Film, General Purpose"
			(at 233.68 228.6 0)
			(effects
				(font
					(size 1.27 1.27)
				)
				(hide yes)
			)
		)
		(property "Manufacturer" "Bourns"
			(at 213.36 251.46 0)
			(effects
				(font
					(size 1.27 1.27)
					(thickness 0.15)
				)
				(justify left bottom)
				(hide yes)
			)
		)
		(property "MPN" "CR0402-FX-51R0GLF"
			(at 213.36 248.92 0)
			(effects
				(font
					(size 1.27 1.27)
					(thickness 0.15)
				)
				(justify left bottom)
				(hide yes)
			)
		)
		(property "Val" "51R"
			(at 237.49 228.6 0)
			(effects
				(font
					(size 1.27 1.27)
					(thickness 0.15)
				)
				(justify left bottom)
			)
		)
		(property "License" "Apache-2.0"
			(at 213.36 254 0)
			(effects
				(font
					(size 1.27 1.27)
					(thickness 0.15)
				)
				(justify left bottom)
				(hide yes)
			)
		)
		(property "Author" "Antmicro"
			(at 213.36 256.54 0)
			(effects
				(font
					(size 1.27 1.27)
					(thickness 0.15)
				)
				(justify left bottom)
				(hide yes)
			)
		)
		(property "Tolerance" "1%"
			(at 213.36 238.76 0)
			(effects
				(font
					(size 1.27 1.27)
				)
				(justify left bottom)
				(hide yes)
			)
		)
		(pin "1"
		)
		(pin "2"
		)
		(instances
			(project "artix-dc-scm"
				(path ""
					(reference "R173")
					(unit 1)
				)
			)
		)
	)
	(symbol
		(lib_id "antmicroResistors0402:R_51R_0402")
		(at 233.68 231.14 0)
		(mirror y)
		(unit 1)
		(exclude_from_sim no)
		(in_bom no)
		(on_board yes)
		(dnp yes)
		(property "Reference" "R174"
			(at 226.06 229.87 0)
			(effects
				(font
					(size 1.27 1.27)
				)
			)
		)
		(property "Value" "R_51R_0402"
			(at 213.36 243.84 0)
			(effects
				(font
					(size 1.27 1.27)
					(thickness 0.15)
				)
				(justify left bottom)
				(hide yes)
			)
		)
		(property "Footprint" "antmicro-footprints:R_0402_1005Metric"
			(at 213.36 246.38 0)
			(effects
				(font
					(size 1.27 1.27)
					(thickness 0.15)
				)
				(justify left bottom)
				(hide yes)
			)
		)
		(property "Datasheet" "https://www.bourns.com/docs/product-datasheets/cr.pdf"
			(at 213.36 248.92 0)
			(effects
				(font
					(size 1.27 1.27)
					(thickness 0.15)
				)
				(justify left bottom)
				(hide yes)
			)
		)
		(property "Description" "SMD Chip Resistor, 51 ohm, ± 1%, 63 mW, 0402 [1005 Metric], Thick Film, General Purpose"
			(at 233.68 231.14 0)
			(effects
				(font
					(size 1.27 1.27)
				)
				(hide yes)
			)
		)
		(property "Manufacturer" "Bourns"
			(at 213.36 254 0)
			(effects
				(font
					(size 1.27 1.27)
					(thickness 0.15)
				)
				(justify left bottom)
				(hide yes)
			)
		)
		(property "MPN" "CR0402-FX-51R0GLF"
			(at 213.36 251.46 0)
			(effects
				(font
					(size 1.27 1.27)
					(thickness 0.15)
				)
				(justify left bottom)
				(hide yes)
			)
		)
		(property "Val" "51R"
			(at 237.49 231.14 0)
			(effects
				(font
					(size 1.27 1.27)
					(thickness 0.15)
				)
				(justify left bottom)
			)
		)
		(property "License" "Apache-2.0"
			(at 213.36 256.54 0)
			(effects
				(font
					(size 1.27 1.27)
					(thickness 0.15)
				)
				(justify left bottom)
				(hide yes)
			)
		)
		(property "Author" "Antmicro"
			(at 213.36 259.08 0)
			(effects
				(font
					(size 1.27 1.27)
					(thickness 0.15)
				)
				(justify left bottom)
				(hide yes)
			)
		)
		(property "Tolerance" "1%"
			(at 213.36 241.3 0)
			(effects
				(font
					(size 1.27 1.27)
				)
				(justify left bottom)
				(hide yes)
			)
		)
		(pin "1"
		)
		(pin "2"
		)
		(instances
			(project "artix-dc-scm"
				(path ""
					(reference "R174")
					(unit 1)
				)
			)
		)
	)
	(symbol
		(lib_id "antmicroResistors0402:R_51R_0402")
		(at 233.68 233.68 0)
		(mirror y)
		(unit 1)
		(exclude_from_sim no)
		(in_bom no)
		(on_board yes)
		(dnp yes)
		(property "Reference" "R175"
			(at 226.06 232.41 0)
			(effects
				(font
					(size 1.27 1.27)
				)
			)
		)
		(property "Value" "R_51R_0402"
			(at 213.36 246.38 0)
			(effects
				(font
					(size 1.27 1.27)
					(thickness 0.15)
				)
				(justify left bottom)
				(hide yes)
			)
		)
		(property "Footprint" "antmicro-footprints:R_0402_1005Metric"
			(at 213.36 248.92 0)
			(effects
				(font
					(size 1.27 1.27)
					(thickness 0.15)
				)
				(justify left bottom)
				(hide yes)
			)
		)
		(property "Datasheet" "https://www.bourns.com/docs/product-datasheets/cr.pdf"
			(at 213.36 251.46 0)
			(effects
				(font
					(size 1.27 1.27)
					(thickness 0.15)
				)
				(justify left bottom)
				(hide yes)
			)
		)
		(property "Description" "SMD Chip Resistor, 51 ohm, ± 1%, 63 mW, 0402 [1005 Metric], Thick Film, General Purpose"
			(at 233.68 233.68 0)
			(effects
				(font
					(size 1.27 1.27)
				)
				(hide yes)
			)
		)
		(property "Manufacturer" "Bourns"
			(at 213.36 256.54 0)
			(effects
				(font
					(size 1.27 1.27)
					(thickness 0.15)
				)
				(justify left bottom)
				(hide yes)
			)
		)
		(property "MPN" "CR0402-FX-51R0GLF"
			(at 213.36 254 0)
			(effects
				(font
					(size 1.27 1.27)
					(thickness 0.15)
				)
				(justify left bottom)
				(hide yes)
			)
		)
		(property "Val" "51R"
			(at 237.49 233.68 0)
			(effects
				(font
					(size 1.27 1.27)
					(thickness 0.15)
				)
				(justify left bottom)
			)
		)
		(property "License" "Apache-2.0"
			(at 213.36 259.08 0)
			(effects
				(font
					(size 1.27 1.27)
					(thickness 0.15)
				)
				(justify left bottom)
				(hide yes)
			)
		)
		(property "Author" "Antmicro"
			(at 213.36 261.62 0)
			(effects
				(font
					(size 1.27 1.27)
					(thickness 0.15)
				)
				(justify left bottom)
				(hide yes)
			)
		)
		(property "Tolerance" "1%"
			(at 213.36 243.84 0)
			(effects
				(font
					(size 1.27 1.27)
				)
				(justify left bottom)
				(hide yes)
			)
		)
		(pin "1"
		)
		(pin "2"
		)
		(instances
			(project "artix-dc-scm"
				(path ""
					(reference "R175")
					(unit 1)
				)
			)
		)
	)
	(symbol
		(lib_id "antmicroResistors0402:R_51R_0402")
		(at 233.68 236.22 0)
		(mirror y)
		(unit 1)
		(exclude_from_sim no)
		(in_bom no)
		(on_board yes)
		(dnp yes)
		(property "Reference" "R176"
			(at 226.06 234.95 0)
			(effects
				(font
					(size 1.27 1.27)
				)
			)
		)
		(property "Value" "R_51R_0402"
			(at 213.36 248.92 0)
			(effects
				(font
					(size 1.27 1.27)
					(thickness 0.15)
				)
				(justify left bottom)
				(hide yes)
			)
		)
		(property "Footprint" "antmicro-footprints:R_0402_1005Metric"
			(at 213.36 251.46 0)
			(effects
				(font
					(size 1.27 1.27)
					(thickness 0.15)
				)
				(justify left bottom)
				(hide yes)
			)
		)
		(property "Datasheet" "https://www.bourns.com/docs/product-datasheets/cr.pdf"
			(at 213.36 254 0)
			(effects
				(font
					(size 1.27 1.27)
					(thickness 0.15)
				)
				(justify left bottom)
				(hide yes)
			)
		)
		(property "Description" "SMD Chip Resistor, 51 ohm, ± 1%, 63 mW, 0402 [1005 Metric], Thick Film, General Purpose"
			(at 233.68 236.22 0)
			(effects
				(font
					(size 1.27 1.27)
				)
				(hide yes)
			)
		)
		(property "Manufacturer" "Bourns"
			(at 213.36 259.08 0)
			(effects
				(font
					(size 1.27 1.27)
					(thickness 0.15)
				)
				(justify left bottom)
				(hide yes)
			)
		)
		(property "MPN" "CR0402-FX-51R0GLF"
			(at 213.36 256.54 0)
			(effects
				(font
					(size 1.27 1.27)
					(thickness 0.15)
				)
				(justify left bottom)
				(hide yes)
			)
		)
		(property "Val" "51R"
			(at 237.49 236.22 0)
			(effects
				(font
					(size 1.27 1.27)
					(thickness 0.15)
				)
				(justify left bottom)
			)
		)
		(property "License" "Apache-2.0"
			(at 213.36 261.62 0)
			(effects
				(font
					(size 1.27 1.27)
					(thickness 0.15)
				)
				(justify left bottom)
				(hide yes)
			)
		)
		(property "Author" "Antmicro"
			(at 213.36 264.16 0)
			(effects
				(font
					(size 1.27 1.27)
					(thickness 0.15)
				)
				(justify left bottom)
				(hide yes)
			)
		)
		(property "Tolerance" "1%"
			(at 213.36 246.38 0)
			(effects
				(font
					(size 1.27 1.27)
				)
				(justify left bottom)
				(hide yes)
			)
		)
		(pin "1"
		)
		(pin "2"
		)
		(instances
			(project "artix-dc-scm"
				(path ""
					(reference "R176")
					(unit 1)
				)
			)
		)
	)
	(symbol
		(lib_id "antmicroResistors0402:R_51R_0402")
		(at 233.68 241.3 0)
		(mirror y)
		(unit 1)
		(exclude_from_sim no)
		(in_bom no)
		(on_board yes)
		(dnp yes)
		(property "Reference" "R177"
			(at 226.06 240.03 0)
			(effects
				(font
					(size 1.27 1.27)
				)
			)
		)
		(property "Value" "R_51R_0402"
			(at 213.36 254 0)
			(effects
				(font
					(size 1.27 1.27)
					(thickness 0.15)
				)
				(justify left bottom)
				(hide yes)
			)
		)
		(property "Footprint" "antmicro-footprints:R_0402_1005Metric"
			(at 213.36 256.54 0)
			(effects
				(font
					(size 1.27 1.27)
					(thickness 0.15)
				)
				(justify left bottom)
				(hide yes)
			)
		)
		(property "Datasheet" "https://www.bourns.com/docs/product-datasheets/cr.pdf"
			(at 213.36 259.08 0)
			(effects
				(font
					(size 1.27 1.27)
					(thickness 0.15)
				)
				(justify left bottom)
				(hide yes)
			)
		)
		(property "Description" "SMD Chip Resistor, 51 ohm, ± 1%, 63 mW, 0402 [1005 Metric], Thick Film, General Purpose"
			(at 233.68 241.3 0)
			(effects
				(font
					(size 1.27 1.27)
				)
				(hide yes)
			)
		)
		(property "Manufacturer" "Bourns"
			(at 213.36 264.16 0)
			(effects
				(font
					(size 1.27 1.27)
					(thickness 0.15)
				)
				(justify left bottom)
				(hide yes)
			)
		)
		(property "MPN" "CR0402-FX-51R0GLF"
			(at 213.36 261.62 0)
			(effects
				(font
					(size 1.27 1.27)
					(thickness 0.15)
				)
				(justify left bottom)
				(hide yes)
			)
		)
		(property "Val" "51R"
			(at 237.49 241.3 0)
			(effects
				(font
					(size 1.27 1.27)
					(thickness 0.15)
				)
				(justify left bottom)
			)
		)
		(property "License" "Apache-2.0"
			(at 213.36 266.7 0)
			(effects
				(font
					(size 1.27 1.27)
					(thickness 0.15)
				)
				(justify left bottom)
				(hide yes)
			)
		)
		(property "Author" "Antmicro"
			(at 213.36 269.24 0)
			(effects
				(font
					(size 1.27 1.27)
					(thickness 0.15)
				)
				(justify left bottom)
				(hide yes)
			)
		)
		(property "Tolerance" "1%"
			(at 213.36 251.46 0)
			(effects
				(font
					(size 1.27 1.27)
				)
				(justify left bottom)
				(hide yes)
			)
		)
		(pin "1"
		)
		(pin "2"
		)
		(instances
			(project "artix-dc-scm"
				(path ""
					(reference "R177")
					(unit 1)
				)
			)
		)
	)
	(symbol
		(lib_id "antmicroResistors0402:R_51R_0402")
		(at 233.68 243.84 0)
		(mirror y)
		(unit 1)
		(exclude_from_sim no)
		(in_bom no)
		(on_board yes)
		(dnp yes)
		(property "Reference" "R178"
			(at 226.06 242.57 0)
			(effects
				(font
					(size 1.27 1.27)
				)
			)
		)
		(property "Value" "R_51R_0402"
			(at 213.36 256.54 0)
			(effects
				(font
					(size 1.27 1.27)
					(thickness 0.15)
				)
				(justify left bottom)
				(hide yes)
			)
		)
		(property "Footprint" "antmicro-footprints:R_0402_1005Metric"
			(at 213.36 259.08 0)
			(effects
				(font
					(size 1.27 1.27)
					(thickness 0.15)
				)
				(justify left bottom)
				(hide yes)
			)
		)
		(property "Datasheet" "https://www.bourns.com/docs/product-datasheets/cr.pdf"
			(at 213.36 261.62 0)
			(effects
				(font
					(size 1.27 1.27)
					(thickness 0.15)
				)
				(justify left bottom)
				(hide yes)
			)
		)
		(property "Description" "SMD Chip Resistor, 51 ohm, ± 1%, 63 mW, 0402 [1005 Metric], Thick Film, General Purpose"
			(at 233.68 243.84 0)
			(effects
				(font
					(size 1.27 1.27)
				)
				(hide yes)
			)
		)
		(property "Manufacturer" "Bourns"
			(at 213.36 266.7 0)
			(effects
				(font
					(size 1.27 1.27)
					(thickness 0.15)
				)
				(justify left bottom)
				(hide yes)
			)
		)
		(property "MPN" "CR0402-FX-51R0GLF"
			(at 213.36 264.16 0)
			(effects
				(font
					(size 1.27 1.27)
					(thickness 0.15)
				)
				(justify left bottom)
				(hide yes)
			)
		)
		(property "Val" "51R"
			(at 237.49 243.84 0)
			(effects
				(font
					(size 1.27 1.27)
					(thickness 0.15)
				)
				(justify left bottom)
			)
		)
		(property "License" "Apache-2.0"
			(at 213.36 269.24 0)
			(effects
				(font
					(size 1.27 1.27)
					(thickness 0.15)
				)
				(justify left bottom)
				(hide yes)
			)
		)
		(property "Author" "Antmicro"
			(at 213.36 271.78 0)
			(effects
				(font
					(size 1.27 1.27)
					(thickness 0.15)
				)
				(justify left bottom)
				(hide yes)
			)
		)
		(property "Tolerance" "1%"
			(at 213.36 254 0)
			(effects
				(font
					(size 1.27 1.27)
				)
				(justify left bottom)
				(hide yes)
			)
		)
		(pin "1"
		)
		(pin "2"
		)
		(instances
			(project "artix-dc-scm"
				(path ""
					(reference "R178")
					(unit 1)
				)
			)
		)
	)
	(symbol
		(lib_id "antmicroResistors0402:R_51R_0402")
		(at 233.68 246.38 0)
		(mirror y)
		(unit 1)
		(exclude_from_sim no)
		(in_bom no)
		(on_board yes)
		(dnp yes)
		(property "Reference" "R179"
			(at 226.06 245.11 0)
			(effects
				(font
					(size 1.27 1.27)
				)
			)
		)
		(property "Value" "R_51R_0402"
			(at 213.36 259.08 0)
			(effects
				(font
					(size 1.27 1.27)
					(thickness 0.15)
				)
				(justify left bottom)
				(hide yes)
			)
		)
		(property "Footprint" "antmicro-footprints:R_0402_1005Metric"
			(at 213.36 261.62 0)
			(effects
				(font
					(size 1.27 1.27)
					(thickness 0.15)
				)
				(justify left bottom)
				(hide yes)
			)
		)
		(property "Datasheet" "https://www.bourns.com/docs/product-datasheets/cr.pdf"
			(at 213.36 264.16 0)
			(effects
				(font
					(size 1.27 1.27)
					(thickness 0.15)
				)
				(justify left bottom)
				(hide yes)
			)
		)
		(property "Description" "SMD Chip Resistor, 51 ohm, ± 1%, 63 mW, 0402 [1005 Metric], Thick Film, General Purpose"
			(at 233.68 246.38 0)
			(effects
				(font
					(size 1.27 1.27)
				)
				(hide yes)
			)
		)
		(property "Manufacturer" "Bourns"
			(at 213.36 269.24 0)
			(effects
				(font
					(size 1.27 1.27)
					(thickness 0.15)
				)
				(justify left bottom)
				(hide yes)
			)
		)
		(property "MPN" "CR0402-FX-51R0GLF"
			(at 213.36 266.7 0)
			(effects
				(font
					(size 1.27 1.27)
					(thickness 0.15)
				)
				(justify left bottom)
				(hide yes)
			)
		)
		(property "Val" "51R"
			(at 237.49 246.38 0)
			(effects
				(font
					(size 1.27 1.27)
					(thickness 0.15)
				)
				(justify left bottom)
			)
		)
		(property "License" "Apache-2.0"
			(at 213.36 271.78 0)
			(effects
				(font
					(size 1.27 1.27)
					(thickness 0.15)
				)
				(justify left bottom)
				(hide yes)
			)
		)
		(property "Author" "Antmicro"
			(at 213.36 274.32 0)
			(effects
				(font
					(size 1.27 1.27)
					(thickness 0.15)
				)
				(justify left bottom)
				(hide yes)
			)
		)
		(property "Tolerance" "1%"
			(at 213.36 256.54 0)
			(effects
				(font
					(size 1.27 1.27)
				)
				(justify left bottom)
				(hide yes)
			)
		)
		(pin "1"
		)
		(pin "2"
		)
		(instances
			(project "artix-dc-scm"
				(path ""
					(reference "R179")
					(unit 1)
				)
			)
		)
	)
	(symbol
		(lib_id "antmicroResistors0402:R_51R_0402")
		(at 233.68 248.92 0)
		(mirror y)
		(unit 1)
		(exclude_from_sim no)
		(in_bom no)
		(on_board yes)
		(dnp yes)
		(property "Reference" "R180"
			(at 226.06 247.65 0)
			(effects
				(font
					(size 1.27 1.27)
				)
			)
		)
		(property "Value" "R_51R_0402"
			(at 213.36 261.62 0)
			(effects
				(font
					(size 1.27 1.27)
					(thickness 0.15)
				)
				(justify left bottom)
				(hide yes)
			)
		)
		(property "Footprint" "antmicro-footprints:R_0402_1005Metric"
			(at 213.36 264.16 0)
			(effects
				(font
					(size 1.27 1.27)
					(thickness 0.15)
				)
				(justify left bottom)
				(hide yes)
			)
		)
		(property "Datasheet" "https://www.bourns.com/docs/product-datasheets/cr.pdf"
			(at 213.36 266.7 0)
			(effects
				(font
					(size 1.27 1.27)
					(thickness 0.15)
				)
				(justify left bottom)
				(hide yes)
			)
		)
		(property "Description" "SMD Chip Resistor, 51 ohm, ± 1%, 63 mW, 0402 [1005 Metric], Thick Film, General Purpose"
			(at 233.68 248.92 0)
			(effects
				(font
					(size 1.27 1.27)
				)
				(hide yes)
			)
		)
		(property "Manufacturer" "Bourns"
			(at 213.36 271.78 0)
			(effects
				(font
					(size 1.27 1.27)
					(thickness 0.15)
				)
				(justify left bottom)
				(hide yes)
			)
		)
		(property "MPN" "CR0402-FX-51R0GLF"
			(at 213.36 269.24 0)
			(effects
				(font
					(size 1.27 1.27)
					(thickness 0.15)
				)
				(justify left bottom)
				(hide yes)
			)
		)
		(property "Val" "51R"
			(at 237.49 248.92 0)
			(effects
				(font
					(size 1.27 1.27)
					(thickness 0.15)
				)
				(justify left bottom)
			)
		)
		(property "License" "Apache-2.0"
			(at 213.36 274.32 0)
			(effects
				(font
					(size 1.27 1.27)
					(thickness 0.15)
				)
				(justify left bottom)
				(hide yes)
			)
		)
		(property "Author" "Antmicro"
			(at 213.36 276.86 0)
			(effects
				(font
					(size 1.27 1.27)
					(thickness 0.15)
				)
				(justify left bottom)
				(hide yes)
			)
		)
		(property "Tolerance" "1%"
			(at 213.36 259.08 0)
			(effects
				(font
					(size 1.27 1.27)
				)
				(justify left bottom)
				(hide yes)
			)
		)
		(pin "1"
		)
		(pin "2"
		)
		(instances
			(project "artix-dc-scm"
				(path ""
					(reference "R180")
					(unit 1)
				)
			)
		)
	)
	(symbol
		(lib_id "antmicroResistors0402:R_51R_0402")
		(at 233.68 251.46 0)
		(mirror y)
		(unit 1)
		(exclude_from_sim no)
		(in_bom no)
		(on_board yes)
		(dnp yes)
		(property "Reference" "R181"
			(at 226.06 250.19 0)
			(effects
				(font
					(size 1.27 1.27)
				)
			)
		)
		(property "Value" "R_51R_0402"
			(at 213.36 264.16 0)
			(effects
				(font
					(size 1.27 1.27)
					(thickness 0.15)
				)
				(justify left bottom)
				(hide yes)
			)
		)
		(property "Footprint" "antmicro-footprints:R_0402_1005Metric"
			(at 213.36 266.7 0)
			(effects
				(font
					(size 1.27 1.27)
					(thickness 0.15)
				)
				(justify left bottom)
				(hide yes)
			)
		)
		(property "Datasheet" "https://www.bourns.com/docs/product-datasheets/cr.pdf"
			(at 213.36 269.24 0)
			(effects
				(font
					(size 1.27 1.27)
					(thickness 0.15)
				)
				(justify left bottom)
				(hide yes)
			)
		)
		(property "Description" "SMD Chip Resistor, 51 ohm, ± 1%, 63 mW, 0402 [1005 Metric], Thick Film, General Purpose"
			(at 233.68 251.46 0)
			(effects
				(font
					(size 1.27 1.27)
				)
				(hide yes)
			)
		)
		(property "Manufacturer" "Bourns"
			(at 213.36 274.32 0)
			(effects
				(font
					(size 1.27 1.27)
					(thickness 0.15)
				)
				(justify left bottom)
				(hide yes)
			)
		)
		(property "MPN" "CR0402-FX-51R0GLF"
			(at 213.36 271.78 0)
			(effects
				(font
					(size 1.27 1.27)
					(thickness 0.15)
				)
				(justify left bottom)
				(hide yes)
			)
		)
		(property "Val" "51R"
			(at 237.49 251.46 0)
			(effects
				(font
					(size 1.27 1.27)
					(thickness 0.15)
				)
				(justify left bottom)
			)
		)
		(property "License" "Apache-2.0"
			(at 213.36 276.86 0)
			(effects
				(font
					(size 1.27 1.27)
					(thickness 0.15)
				)
				(justify left bottom)
				(hide yes)
			)
		)
		(property "Author" "Antmicro"
			(at 213.36 279.4 0)
			(effects
				(font
					(size 1.27 1.27)
					(thickness 0.15)
				)
				(justify left bottom)
				(hide yes)
			)
		)
		(property "Tolerance" "1%"
			(at 213.36 261.62 0)
			(effects
				(font
					(size 1.27 1.27)
				)
				(justify left bottom)
				(hide yes)
			)
		)
		(pin "1"
		)
		(pin "2"
		)
		(instances
			(project "artix-dc-scm"
				(path ""
					(reference "R181")
					(unit 1)
				)
			)
		)
	)
	(symbol
		(lib_id "antmicroResistors0402:R_51R_0402")
		(at 233.68 254 0)
		(mirror y)
		(unit 1)
		(exclude_from_sim no)
		(in_bom no)
		(on_board yes)
		(dnp yes)
		(property "Reference" "R182"
			(at 226.06 252.73 0)
			(effects
				(font
					(size 1.27 1.27)
				)
			)
		)
		(property "Value" "R_51R_0402"
			(at 213.36 266.7 0)
			(effects
				(font
					(size 1.27 1.27)
					(thickness 0.15)
				)
				(justify left bottom)
				(hide yes)
			)
		)
		(property "Footprint" "antmicro-footprints:R_0402_1005Metric"
			(at 213.36 269.24 0)
			(effects
				(font
					(size 1.27 1.27)
					(thickness 0.15)
				)
				(justify left bottom)
				(hide yes)
			)
		)
		(property "Datasheet" "https://www.bourns.com/docs/product-datasheets/cr.pdf"
			(at 213.36 271.78 0)
			(effects
				(font
					(size 1.27 1.27)
					(thickness 0.15)
				)
				(justify left bottom)
				(hide yes)
			)
		)
		(property "Description" "SMD Chip Resistor, 51 ohm, ± 1%, 63 mW, 0402 [1005 Metric], Thick Film, General Purpose"
			(at 233.68 254 0)
			(effects
				(font
					(size 1.27 1.27)
				)
				(hide yes)
			)
		)
		(property "Manufacturer" "Bourns"
			(at 213.36 276.86 0)
			(effects
				(font
					(size 1.27 1.27)
					(thickness 0.15)
				)
				(justify left bottom)
				(hide yes)
			)
		)
		(property "MPN" "CR0402-FX-51R0GLF"
			(at 213.36 274.32 0)
			(effects
				(font
					(size 1.27 1.27)
					(thickness 0.15)
				)
				(justify left bottom)
				(hide yes)
			)
		)
		(property "Val" "51R"
			(at 237.49 254 0)
			(effects
				(font
					(size 1.27 1.27)
					(thickness 0.15)
				)
				(justify left bottom)
			)
		)
		(property "License" "Apache-2.0"
			(at 213.36 279.4 0)
			(effects
				(font
					(size 1.27 1.27)
					(thickness 0.15)
				)
				(justify left bottom)
				(hide yes)
			)
		)
		(property "Author" "Antmicro"
			(at 213.36 281.94 0)
			(effects
				(font
					(size 1.27 1.27)
					(thickness 0.15)
				)
				(justify left bottom)
				(hide yes)
			)
		)
		(property "Tolerance" "1%"
			(at 213.36 264.16 0)
			(effects
				(font
					(size 1.27 1.27)
				)
				(justify left bottom)
				(hide yes)
			)
		)
		(pin "1"
		)
		(pin "2"
		)
		(instances
			(project "artix-dc-scm"
				(path ""
					(reference "R182")
					(unit 1)
				)
			)
		)
	)
	(symbol
		(lib_id "antmicroResistors0402:R_51R_0402")
		(at 233.68 256.54 0)
		(mirror y)
		(unit 1)
		(exclude_from_sim no)
		(in_bom no)
		(on_board yes)
		(dnp yes)
		(property "Reference" "R183"
			(at 226.06 255.27 0)
			(effects
				(font
					(size 1.27 1.27)
				)
			)
		)
		(property "Value" "R_51R_0402"
			(at 213.36 269.24 0)
			(effects
				(font
					(size 1.27 1.27)
					(thickness 0.15)
				)
				(justify left bottom)
				(hide yes)
			)
		)
		(property "Footprint" "antmicro-footprints:R_0402_1005Metric"
			(at 213.36 271.78 0)
			(effects
				(font
					(size 1.27 1.27)
					(thickness 0.15)
				)
				(justify left bottom)
				(hide yes)
			)
		)
		(property "Datasheet" "https://www.bourns.com/docs/product-datasheets/cr.pdf"
			(at 213.36 274.32 0)
			(effects
				(font
					(size 1.27 1.27)
					(thickness 0.15)
				)
				(justify left bottom)
				(hide yes)
			)
		)
		(property "Description" "SMD Chip Resistor, 51 ohm, ± 1%, 63 mW, 0402 [1005 Metric], Thick Film, General Purpose"
			(at 233.68 256.54 0)
			(effects
				(font
					(size 1.27 1.27)
				)
				(hide yes)
			)
		)
		(property "Manufacturer" "Bourns"
			(at 213.36 279.4 0)
			(effects
				(font
					(size 1.27 1.27)
					(thickness 0.15)
				)
				(justify left bottom)
				(hide yes)
			)
		)
		(property "MPN" "CR0402-FX-51R0GLF"
			(at 213.36 276.86 0)
			(effects
				(font
					(size 1.27 1.27)
					(thickness 0.15)
				)
				(justify left bottom)
				(hide yes)
			)
		)
		(property "Val" "51R"
			(at 237.49 256.54 0)
			(effects
				(font
					(size 1.27 1.27)
					(thickness 0.15)
				)
				(justify left bottom)
			)
		)
		(property "License" "Apache-2.0"
			(at 213.36 281.94 0)
			(effects
				(font
					(size 1.27 1.27)
					(thickness 0.15)
				)
				(justify left bottom)
				(hide yes)
			)
		)
		(property "Author" "Antmicro"
			(at 213.36 284.48 0)
			(effects
				(font
					(size 1.27 1.27)
					(thickness 0.15)
				)
				(justify left bottom)
				(hide yes)
			)
		)
		(property "Tolerance" "1%"
			(at 213.36 266.7 0)
			(effects
				(font
					(size 1.27 1.27)
				)
				(justify left bottom)
				(hide yes)
			)
		)
		(pin "1"
		)
		(pin "2"
		)
		(instances
			(project "artix-dc-scm"
				(path ""
					(reference "R183")
					(unit 1)
				)
			)
		)
	)
	(symbol
		(lib_id "antmicroResistors0402:R_51R_0402")
		(at 233.68 259.08 0)
		(mirror y)
		(unit 1)
		(exclude_from_sim no)
		(in_bom no)
		(on_board yes)
		(dnp yes)
		(property "Reference" "R184"
			(at 226.06 257.81 0)
			(effects
				(font
					(size 1.27 1.27)
				)
			)
		)
		(property "Value" "R_51R_0402"
			(at 213.36 271.78 0)
			(effects
				(font
					(size 1.27 1.27)
					(thickness 0.15)
				)
				(justify left bottom)
				(hide yes)
			)
		)
		(property "Footprint" "antmicro-footprints:R_0402_1005Metric"
			(at 213.36 274.32 0)
			(effects
				(font
					(size 1.27 1.27)
					(thickness 0.15)
				)
				(justify left bottom)
				(hide yes)
			)
		)
		(property "Datasheet" "https://www.bourns.com/docs/product-datasheets/cr.pdf"
			(at 213.36 276.86 0)
			(effects
				(font
					(size 1.27 1.27)
					(thickness 0.15)
				)
				(justify left bottom)
				(hide yes)
			)
		)
		(property "Description" "SMD Chip Resistor, 51 ohm, ± 1%, 63 mW, 0402 [1005 Metric], Thick Film, General Purpose"
			(at 233.68 259.08 0)
			(effects
				(font
					(size 1.27 1.27)
				)
				(hide yes)
			)
		)
		(property "Manufacturer" "Bourns"
			(at 213.36 281.94 0)
			(effects
				(font
					(size 1.27 1.27)
					(thickness 0.15)
				)
				(justify left bottom)
				(hide yes)
			)
		)
		(property "MPN" "CR0402-FX-51R0GLF"
			(at 213.36 279.4 0)
			(effects
				(font
					(size 1.27 1.27)
					(thickness 0.15)
				)
				(justify left bottom)
				(hide yes)
			)
		)
		(property "Val" "51R"
			(at 237.49 259.08 0)
			(effects
				(font
					(size 1.27 1.27)
					(thickness 0.15)
				)
				(justify left bottom)
			)
		)
		(property "License" "Apache-2.0"
			(at 213.36 284.48 0)
			(effects
				(font
					(size 1.27 1.27)
					(thickness 0.15)
				)
				(justify left bottom)
				(hide yes)
			)
		)
		(property "Author" "Antmicro"
			(at 213.36 287.02 0)
			(effects
				(font
					(size 1.27 1.27)
					(thickness 0.15)
				)
				(justify left bottom)
				(hide yes)
			)
		)
		(property "Tolerance" "1%"
			(at 213.36 269.24 0)
			(effects
				(font
					(size 1.27 1.27)
				)
				(justify left bottom)
				(hide yes)
			)
		)
		(pin "1"
		)
		(pin "2"
		)
		(instances
			(project "artix-dc-scm"
				(path ""
					(reference "R184")
					(unit 1)
				)
			)
		)
	)
	(symbol
		(lib_id "antmicropower:GND")
		(at 170.18 220.98 0)
		(mirror y)
		(unit 1)
		(exclude_from_sim no)
		(in_bom yes)
		(on_board yes)
		(dnp no)
		(property "Reference" "#PWR038"
			(at 170.18 227.33 0)
			(effects
				(font
					(size 1.27 1.27)
				)
				(hide yes)
			)
		)
		(property "Value" "GND"
			(at 170.18 224.79 0)
			(effects
				(font
					(size 1.27 1.27)
				)
			)
		)
		(property "Footprint" ""
			(at 170.18 220.98 0)
			(effects
				(font
					(size 1.27 1.27)
				)
				(hide yes)
			)
		)
		(property "Datasheet" ""
			(at 170.18 220.98 0)
			(effects
				(font
					(size 1.27 1.27)
				)
				(hide yes)
			)
		)
		(property "Description" ""
			(at 170.18 220.98 0)
			(effects
				(font
					(size 1.27 1.27)
				)
				(hide yes)
			)
		)
		(property "Author" "Antmicro"
			(at 161.29 228.6 0)
			(effects
				(font
					(size 1.27 1.27)
					(thickness 0.15)
				)
				(justify left bottom)
				(hide yes)
			)
		)
		(property "License" "Apache-2.0"
			(at 161.29 231.14 0)
			(effects
				(font
					(size 1.27 1.27)
					(thickness 0.15)
				)
				(justify left bottom)
				(hide yes)
			)
		)
		(pin "1"
		)
		(instances
			(project "artix-dc-scm"
				(path ""
					(reference "#PWR038")
					(unit 1)
				)
			)
		)
	)
	(symbol
		(lib_id "antmicroResistors0402:R_10k_0402")
		(at 105.41 198.12 90)
		(mirror x)
		(unit 1)
		(exclude_from_sim no)
		(in_bom yes)
		(on_board yes)
		(dnp no)
		(property "Reference" "R58"
			(at 106.68 199.39 90)
			(effects
				(font
					(size 1.27 1.27)
				)
				(justify right)
			)
		)
		(property "Value" "R_10k_0402"
			(at 118.11 218.44 0)
			(effects
				(font
					(size 1.27 1.27)
					(thickness 0.15)
				)
				(justify left bottom)
				(hide yes)
			)
		)
		(property "Footprint" "antmicro-footprints:R_0402_1005Metric"
			(at 120.65 218.44 0)
			(effects
				(font
					(size 1.27 1.27)
					(thickness 0.15)
				)
				(justify left bottom)
				(hide yes)
			)
		)
		(property "Datasheet" "https://www.bourns.com/docs/product-datasheets/cr.pdf"
			(at 123.19 218.44 0)
			(effects
				(font
					(size 1.27 1.27)
					(thickness 0.15)
				)
				(justify left bottom)
				(hide yes)
			)
		)
		(property "Description" "SMD Chip Resistor, 10 kohm, ± 1%, 62.5 mW, 0402 [1005 Metric], Thick Film, General Purpose"
			(at 105.41 198.12 0)
			(effects
				(font
					(size 1.27 1.27)
				)
				(hide yes)
			)
		)
		(property "Manufacturer" "Bourns"
			(at 128.27 218.44 0)
			(effects
				(font
					(size 1.27 1.27)
					(thickness 0.15)
				)
				(justify left bottom)
				(hide yes)
			)
		)
		(property "MPN" "CR0402-FX-1002GLF"
			(at 125.73 218.44 0)
			(effects
				(font
					(size 1.27 1.27)
					(thickness 0.15)
				)
				(justify left bottom)
				(hide yes)
			)
		)
		(property "Val" "10k"
			(at 106.68 201.93 90)
			(effects
				(font
					(size 1.27 1.27)
					(thickness 0.15)
				)
				(justify right)
			)
		)
		(property "License" "Apache-2.0"
			(at 130.81 218.44 0)
			(effects
				(font
					(size 1.27 1.27)
					(thickness 0.15)
				)
				(justify left bottom)
				(hide yes)
			)
		)
		(property "Author" "Antmicro"
			(at 133.35 218.44 0)
			(effects
				(font
					(size 1.27 1.27)
					(thickness 0.15)
				)
				(justify left bottom)
				(hide yes)
			)
		)
		(property "Tolerance" "1%"
			(at 115.57 218.44 0)
			(effects
				(font
					(size 1.27 1.27)
				)
				(justify left bottom)
				(hide yes)
			)
		)
		(pin "1"
		)
		(pin "2"
		)
		(instances
			(project "artix-dc-scm"
				(path ""
					(reference "R58")
					(unit 1)
				)
			)
		)
	)
	(symbol
		(lib_id "antmicroResistors0402:R_10k_0402")
		(at 123.19 186.69 90)
		(mirror x)
		(unit 1)
		(exclude_from_sim no)
		(in_bom yes)
		(on_board yes)
		(dnp no)
		(property "Reference" "R59"
			(at 124.46 187.96 90)
			(effects
				(font
					(size 1.27 1.27)
				)
				(justify right)
			)
		)
		(property "Value" "R_10k_0402"
			(at 135.89 207.01 0)
			(effects
				(font
					(size 1.27 1.27)
					(thickness 0.15)
				)
				(justify left bottom)
				(hide yes)
			)
		)
		(property "Footprint" "antmicro-footprints:R_0402_1005Metric"
			(at 138.43 207.01 0)
			(effects
				(font
					(size 1.27 1.27)
					(thickness 0.15)
				)
				(justify left bottom)
				(hide yes)
			)
		)
		(property "Datasheet" "https://www.bourns.com/docs/product-datasheets/cr.pdf"
			(at 140.97 207.01 0)
			(effects
				(font
					(size 1.27 1.27)
					(thickness 0.15)
				)
				(justify left bottom)
				(hide yes)
			)
		)
		(property "Description" "SMD Chip Resistor, 10 kohm, ± 1%, 62.5 mW, 0402 [1005 Metric], Thick Film, General Purpose"
			(at 123.19 186.69 0)
			(effects
				(font
					(size 1.27 1.27)
				)
				(hide yes)
			)
		)
		(property "Manufacturer" "Bourns"
			(at 146.05 207.01 0)
			(effects
				(font
					(size 1.27 1.27)
					(thickness 0.15)
				)
				(justify left bottom)
				(hide yes)
			)
		)
		(property "MPN" "CR0402-FX-1002GLF"
			(at 143.51 207.01 0)
			(effects
				(font
					(size 1.27 1.27)
					(thickness 0.15)
				)
				(justify left bottom)
				(hide yes)
			)
		)
		(property "Val" "10k"
			(at 124.46 190.5 90)
			(effects
				(font
					(size 1.27 1.27)
					(thickness 0.15)
				)
				(justify right)
			)
		)
		(property "License" "Apache-2.0"
			(at 148.59 207.01 0)
			(effects
				(font
					(size 1.27 1.27)
					(thickness 0.15)
				)
				(justify left bottom)
				(hide yes)
			)
		)
		(property "Author" "Antmicro"
			(at 151.13 207.01 0)
			(effects
				(font
					(size 1.27 1.27)
					(thickness 0.15)
				)
				(justify left bottom)
				(hide yes)
			)
		)
		(property "Tolerance" "1%"
			(at 133.35 207.01 0)
			(effects
				(font
					(size 1.27 1.27)
				)
				(justify left bottom)
				(hide yes)
			)
		)
		(pin "1"
		)
		(pin "2"
		)
		(instances
			(project "artix-dc-scm"
				(path ""
					(reference "R59")
					(unit 1)
				)
			)
		)
	)
	(symbol
		(lib_id "antmicropower:GND")
		(at 185.42 204.47 0)
		(mirror y)
		(unit 1)
		(exclude_from_sim no)
		(in_bom yes)
		(on_board yes)
		(dnp no)
		(property "Reference" "#PWR036"
			(at 185.42 210.82 0)
			(effects
				(font
					(size 1.27 1.27)
				)
				(hide yes)
			)
		)
		(property "Value" "GND"
			(at 185.42 208.28 0)
			(effects
				(font
					(size 1.27 1.27)
				)
			)
		)
		(property "Footprint" ""
			(at 185.42 204.47 0)
			(effects
				(font
					(size 1.27 1.27)
				)
				(hide yes)
			)
		)
		(property "Datasheet" ""
			(at 185.42 204.47 0)
			(effects
				(font
					(size 1.27 1.27)
				)
				(hide yes)
			)
		)
		(property "Description" ""
			(at 185.42 204.47 0)
			(effects
				(font
					(size 1.27 1.27)
				)
				(hide yes)
			)
		)
		(property "Author" "Antmicro"
			(at 176.53 212.09 0)
			(effects
				(font
					(size 1.27 1.27)
					(thickness 0.15)
				)
				(justify left bottom)
				(hide yes)
			)
		)
		(property "License" "Apache-2.0"
			(at 176.53 214.63 0)
			(effects
				(font
					(size 1.27 1.27)
					(thickness 0.15)
				)
				(justify left bottom)
				(hide yes)
			)
		)
		(pin "1"
		)
		(instances
			(project "artix-dc-scm"
				(path ""
					(reference "#PWR036")
					(unit 1)
				)
			)
		)
	)
	(symbol
		(lib_id "antmicropower:GND")
		(at 114.3 228.6 0)
		(mirror y)
		(unit 1)
		(exclude_from_sim no)
		(in_bom yes)
		(on_board yes)
		(dnp no)
		(property "Reference" "#PWR040"
			(at 114.3 234.95 0)
			(effects
				(font
					(size 1.27 1.27)
				)
				(hide yes)
			)
		)
		(property "Value" "GND"
			(at 114.3 232.41 0)
			(effects
				(font
					(size 1.27 1.27)
				)
			)
		)
		(property "Footprint" ""
			(at 114.3 228.6 0)
			(effects
				(font
					(size 1.27 1.27)
				)
				(hide yes)
			)
		)
		(property "Datasheet" ""
			(at 114.3 228.6 0)
			(effects
				(font
					(size 1.27 1.27)
				)
				(hide yes)
			)
		)
		(property "Description" ""
			(at 114.3 228.6 0)
			(effects
				(font
					(size 1.27 1.27)
				)
				(hide yes)
			)
		)
		(property "Author" "Antmicro"
			(at 105.41 236.22 0)
			(effects
				(font
					(size 1.27 1.27)
					(thickness 0.15)
				)
				(justify left bottom)
				(hide yes)
			)
		)
		(property "License" "Apache-2.0"
			(at 105.41 238.76 0)
			(effects
				(font
					(size 1.27 1.27)
					(thickness 0.15)
				)
				(justify left bottom)
				(hide yes)
			)
		)
		(pin "1"
		)
		(instances
			(project "artix-dc-scm"
				(path ""
					(reference "#PWR040")
					(unit 1)
				)
			)
		)
	)
	(symbol
		(lib_id "antmicropower:GND")
		(at 151.13 212.09 0)
		(mirror y)
		(unit 1)
		(exclude_from_sim no)
		(in_bom yes)
		(on_board yes)
		(dnp no)
		(property "Reference" "#PWR039"
			(at 151.13 218.44 0)
			(effects
				(font
					(size 1.27 1.27)
				)
				(hide yes)
			)
		)
		(property "Value" "GND"
			(at 151.13 215.9 0)
			(effects
				(font
					(size 1.27 1.27)
				)
			)
		)
		(property "Footprint" ""
			(at 151.13 212.09 0)
			(effects
				(font
					(size 1.27 1.27)
				)
				(hide yes)
			)
		)
		(property "Datasheet" ""
			(at 151.13 212.09 0)
			(effects
				(font
					(size 1.27 1.27)
				)
				(hide yes)
			)
		)
		(property "Description" ""
			(at 151.13 212.09 0)
			(effects
				(font
					(size 1.27 1.27)
				)
				(hide yes)
			)
		)
		(property "Author" "Antmicro"
			(at 142.24 219.71 0)
			(effects
				(font
					(size 1.27 1.27)
					(thickness 0.15)
				)
				(justify left bottom)
				(hide yes)
			)
		)
		(property "License" "Apache-2.0"
			(at 142.24 222.25 0)
			(effects
				(font
					(size 1.27 1.27)
					(thickness 0.15)
				)
				(justify left bottom)
				(hide yes)
			)
		)
		(pin "1"
		)
		(instances
			(project "artix-dc-scm"
				(path ""
					(reference "#PWR039")
					(unit 1)
				)
			)
		)
	)
	(symbol
		(lib_id "antmicroCapacitors0402:C_10u_0402")
		(at 107.95 191.77 270)
		(mirror x)
		(unit 1)
		(exclude_from_sim no)
		(in_bom yes)
		(on_board yes)
		(dnp no)
		(property "Reference" "C47"
			(at 108.585 187.325 90)
			(effects
				(font
					(size 1.27 1.27)
				)
				(justify left)
			)
		)
		(property "Value" "C_10u_0402"
			(at 97.79 171.45 0)
			(effects
				(font
					(size 1.27 1.27)
					(thickness 0.15)
				)
				(justify left bottom)
				(hide yes)
			)
		)
		(property "Footprint" "antmicro-footprints:C_0402_1005Metric"
			(at 95.25 171.45 0)
			(effects
				(font
					(size 1.27 1.27)
					(thickness 0.15)
				)
				(justify left bottom)
				(hide yes)
			)
		)
		(property "Datasheet" "https://www.yageo.com/en/Chart/Download/pdf/CC0402MRX5R5BB106"
			(at 92.71 171.45 0)
			(effects
				(font
					(size 1.27 1.27)
					(thickness 0.15)
				)
				(justify left bottom)
				(hide yes)
			)
		)
		(property "Description" "SMD Multilayer Ceramic Capacitor, 10 µF, 6.3 V, 0402 [1005 Metric], ± 20%, X5R, CC Series"
			(at 107.95 191.77 0)
			(effects
				(font
					(size 1.27 1.27)
				)
				(hide yes)
			)
		)
		(property "Manufacturer" "YAGEO"
			(at 87.63 171.45 0)
			(effects
				(font
					(size 1.27 1.27)
					(thickness 0.15)
				)
				(justify left bottom)
				(hide yes)
			)
		)
		(property "MPN" "CC0402MRX5R5BB106"
			(at 90.17 171.45 0)
			(effects
				(font
					(size 1.27 1.27)
					(thickness 0.15)
				)
				(justify left bottom)
				(hide yes)
			)
		)
		(property "Val" "10u"
			(at 108.585 191.135 90)
			(effects
				(font
					(size 1.27 1.27)
					(thickness 0.15)
				)
				(justify left)
			)
		)
		(property "License" "Apache-2.0"
			(at 85.09 171.45 0)
			(effects
				(font
					(size 1.27 1.27)
					(thickness 0.15)
				)
				(justify left bottom)
				(hide yes)
			)
		)
		(property "Author" "Antmicro"
			(at 82.55 171.45 0)
			(effects
				(font
					(size 1.27 1.27)
					(thickness 0.15)
				)
				(justify left bottom)
				(hide yes)
			)
		)
		(property "Voltage" ""
			(at 80.01 171.45 0)
			(effects
				(font
					(size 1.27 1.27)
				)
				(justify left bottom)
				(hide yes)
			)
		)
		(property "Dielectric" ""
			(at 77.47 171.45 0)
			(effects
				(font
					(size 1.27 1.27)
				)
				(justify left bottom)
				(hide yes)
			)
		)
		(pin "1"
		)
		(pin "2"
		)
		(instances
			(project "artix-dc-scm"
				(path ""
					(reference "C47")
					(unit 1)
				)
			)
		)
	)
	(symbol
		(lib_id "antmicropower:GND")
		(at 107.95 191.77 0)
		(mirror y)
		(unit 1)
		(exclude_from_sim no)
		(in_bom yes)
		(on_board yes)
		(dnp no)
		(property "Reference" "#PWR041"
			(at 107.95 198.12 0)
			(effects
				(font
					(size 1.27 1.27)
				)
				(hide yes)
			)
		)
		(property "Value" "GND"
			(at 107.95 195.58 0)
			(effects
				(font
					(size 1.27 1.27)
				)
			)
		)
		(property "Footprint" ""
			(at 107.95 191.77 0)
			(effects
				(font
					(size 1.27 1.27)
				)
				(hide yes)
			)
		)
		(property "Datasheet" ""
			(at 107.95 191.77 0)
			(effects
				(font
					(size 1.27 1.27)
				)
				(hide yes)
			)
		)
		(property "Description" ""
			(at 107.95 191.77 0)
			(effects
				(font
					(size 1.27 1.27)
				)
				(hide yes)
			)
		)
		(property "Author" "Antmicro"
			(at 99.06 199.39 0)
			(effects
				(font
					(size 1.27 1.27)
					(thickness 0.15)
				)
				(justify left bottom)
				(hide yes)
			)
		)
		(property "License" "Apache-2.0"
			(at 99.06 201.93 0)
			(effects
				(font
					(size 1.27 1.27)
					(thickness 0.15)
				)
				(justify left bottom)
				(hide yes)
			)
		)
		(pin "1"
		)
		(instances
			(project "artix-dc-scm"
				(path ""
					(reference "#PWR041")
					(unit 1)
				)
			)
		)
	)
	(symbol
		(lib_id "antmicropower:GND")
		(at 130.81 46.99 0)
		(unit 1)
		(exclude_from_sim no)
		(in_bom yes)
		(on_board yes)
		(dnp no)
		(property "Reference" "#PWR042"
			(at 130.81 53.34 0)
			(effects
				(font
					(size 1.27 1.27)
				)
				(hide yes)
			)
		)
		(property "Value" "GND"
			(at 130.81 50.8 0)
			(effects
				(font
					(size 1.27 1.27)
				)
			)
		)
		(property "Footprint" ""
			(at 130.81 46.99 0)
			(effects
				(font
					(size 1.27 1.27)
				)
				(hide yes)
			)
		)
		(property "Datasheet" ""
			(at 130.81 46.99 0)
			(effects
				(font
					(size 1.27 1.27)
				)
				(hide yes)
			)
		)
		(property "Description" ""
			(at 130.81 46.99 0)
			(effects
				(font
					(size 1.27 1.27)
				)
				(hide yes)
			)
		)
		(property "Author" "Antmicro"
			(at 139.7 54.61 0)
			(effects
				(font
					(size 1.27 1.27)
					(thickness 0.15)
				)
				(justify left bottom)
				(hide yes)
			)
		)
		(property "License" "Apache-2.0"
			(at 139.7 57.15 0)
			(effects
				(font
					(size 1.27 1.27)
					(thickness 0.15)
				)
				(justify left bottom)
				(hide yes)
			)
		)
		(pin "1"
		)
		(instances
			(project "artix-dc-scm"
				(path ""
					(reference "#PWR042")
					(unit 1)
				)
			)
		)
	)
	(symbol
		(lib_id "antmicropower:GND")
		(at 139.7 60.96 0)
		(unit 1)
		(exclude_from_sim no)
		(in_bom yes)
		(on_board yes)
		(dnp no)
		(property "Reference" "#PWR043"
			(at 139.7 67.31 0)
			(effects
				(font
					(size 1.27 1.27)
				)
				(hide yes)
			)
		)
		(property "Value" "GND"
			(at 139.7 64.77 0)
			(effects
				(font
					(size 1.27 1.27)
				)
			)
		)
		(property "Footprint" ""
			(at 139.7 60.96 0)
			(effects
				(font
					(size 1.27 1.27)
				)
				(hide yes)
			)
		)
		(property "Datasheet" ""
			(at 139.7 60.96 0)
			(effects
				(font
					(size 1.27 1.27)
				)
				(hide yes)
			)
		)
		(property "Description" ""
			(at 139.7 60.96 0)
			(effects
				(font
					(size 1.27 1.27)
				)
				(hide yes)
			)
		)
		(property "Author" "Antmicro"
			(at 148.59 68.58 0)
			(effects
				(font
					(size 1.27 1.27)
					(thickness 0.15)
				)
				(justify left bottom)
				(hide yes)
			)
		)
		(property "License" "Apache-2.0"
			(at 148.59 71.12 0)
			(effects
				(font
					(size 1.27 1.27)
					(thickness 0.15)
				)
				(justify left bottom)
				(hide yes)
			)
		)
		(pin "1"
		)
		(instances
			(project "artix-dc-scm"
				(path ""
					(reference "#PWR043")
					(unit 1)
				)
			)
		)
	)
	(symbol
		(lib_id "antmicropower:GND")
		(at 243.84 60.96 0)
		(mirror y)
		(unit 1)
		(exclude_from_sim no)
		(in_bom yes)
		(on_board yes)
		(dnp no)
		(property "Reference" "#PWR044"
			(at 243.84 67.31 0)
			(effects
				(font
					(size 1.27 1.27)
				)
				(hide yes)
			)
		)
		(property "Value" "GND"
			(at 243.84 64.77 0)
			(effects
				(font
					(size 1.27 1.27)
				)
			)
		)
		(property "Footprint" ""
			(at 243.84 60.96 0)
			(effects
				(font
					(size 1.27 1.27)
				)
				(hide yes)
			)
		)
		(property "Datasheet" ""
			(at 243.84 60.96 0)
			(effects
				(font
					(size 1.27 1.27)
				)
				(hide yes)
			)
		)
		(property "Description" ""
			(at 243.84 60.96 0)
			(effects
				(font
					(size 1.27 1.27)
				)
				(hide yes)
			)
		)
		(property "Author" "Antmicro"
			(at 234.95 68.58 0)
			(effects
				(font
					(size 1.27 1.27)
					(thickness 0.15)
				)
				(justify left bottom)
				(hide yes)
			)
		)
		(property "License" "Apache-2.0"
			(at 234.95 71.12 0)
			(effects
				(font
					(size 1.27 1.27)
					(thickness 0.15)
				)
				(justify left bottom)
				(hide yes)
			)
		)
		(pin "1"
		)
		(instances
			(project "artix-dc-scm"
				(path ""
					(reference "#PWR044")
					(unit 1)
				)
			)
		)
	)
	(symbol
		(lib_id "antmicropower:GND")
		(at 114.3 97.79 0)
		(unit 1)
		(exclude_from_sim no)
		(in_bom yes)
		(on_board yes)
		(dnp no)
		(property "Reference" "#PWR045"
			(at 114.3 104.14 0)
			(effects
				(font
					(size 1.27 1.27)
				)
				(hide yes)
			)
		)
		(property "Value" "GND"
			(at 114.3 101.6 0)
			(effects
				(font
					(size 1.27 1.27)
				)
			)
		)
		(property "Footprint" ""
			(at 114.3 97.79 0)
			(effects
				(font
					(size 1.27 1.27)
				)
				(hide yes)
			)
		)
		(property "Datasheet" ""
			(at 114.3 97.79 0)
			(effects
				(font
					(size 1.27 1.27)
				)
				(hide yes)
			)
		)
		(property "Description" ""
			(at 114.3 97.79 0)
			(effects
				(font
					(size 1.27 1.27)
				)
				(hide yes)
			)
		)
		(property "Author" "Antmicro"
			(at 123.19 105.41 0)
			(effects
				(font
					(size 1.27 1.27)
					(thickness 0.15)
				)
				(justify left bottom)
				(hide yes)
			)
		)
		(property "License" "Apache-2.0"
			(at 123.19 107.95 0)
			(effects
				(font
					(size 1.27 1.27)
					(thickness 0.15)
				)
				(justify left bottom)
				(hide yes)
			)
		)
		(pin "1"
		)
		(instances
			(project "artix-dc-scm"
				(path ""
					(reference "#PWR045")
					(unit 1)
				)
			)
		)
	)
	(symbol
		(lib_id "antmicroCapacitorsmisc:C_100n_6V3_0402")
		(at 114.3 228.6 90)
		(unit 1)
		(exclude_from_sim no)
		(in_bom yes)
		(on_board yes)
		(dnp no)
		(property "Reference" "C46"
			(at 114.935 224.155 90)
			(effects
				(font
					(size 1.27 1.27)
				)
				(justify right)
			)
		)
		(property "Value" "C_100n_6V3_0402"
			(at 124.46 208.28 0)
			(effects
				(font
					(size 1.27 1.27)
					(thickness 0.15)
				)
				(justify left bottom)
				(hide yes)
			)
		)
		(property "Footprint" "antmicro-footprints:C_0402_1005Metric"
			(at 127 208.28 0)
			(effects
				(font
					(size 1.27 1.27)
					(thickness 0.15)
				)
				(justify left bottom)
				(hide yes)
			)
		)
		(property "Datasheet" "https://www.passivecomponent.com/wp-content/uploads/datasheet/WTC_MLCC_General_Purpose.pdf"
			(at 129.54 208.28 0)
			(effects
				(font
					(size 1.27 1.27)
					(thickness 0.15)
				)
				(justify left bottom)
				(hide yes)
			)
		)
		(property "Description" "SMT Multilayer Ceramic Capacitor, 0.1 µF, 6.3 V, 0402 [1005 Metric], ± 10%, X5R, Walsin MLCC"
			(at 114.3 228.6 0)
			(effects
				(font
					(size 1.27 1.27)
				)
				(hide yes)
			)
		)
		(property "Manufacturer" "Walsin"
			(at 134.62 208.28 0)
			(effects
				(font
					(size 1.27 1.27)
					(thickness 0.15)
				)
				(justify left bottom)
				(hide yes)
			)
		)
		(property "MPN" "0402X104K6R3CT"
			(at 132.08 208.28 0)
			(effects
				(font
					(size 1.27 1.27)
					(thickness 0.15)
				)
				(justify left bottom)
				(hide yes)
			)
		)
		(property "Val" "100n"
			(at 114.935 228.6 90)
			(effects
				(font
					(size 1.27 1.27)
					(thickness 0.15)
				)
				(justify right)
			)
		)
		(property "License" "Apache-2.0"
			(at 137.16 208.28 0)
			(effects
				(font
					(size 1.27 1.27)
					(thickness 0.15)
				)
				(justify left bottom)
				(hide yes)
			)
		)
		(property "Author" "Antmicro"
			(at 139.7 208.28 0)
			(effects
				(font
					(size 1.27 1.27)
					(thickness 0.15)
				)
				(justify left bottom)
				(hide yes)
			)
		)
		(property "Voltage" ""
			(at 142.24 208.28 0)
			(effects
				(font
					(size 1.27 1.27)
				)
				(justify left bottom)
				(hide yes)
			)
		)
		(property "Dielectric" ""
			(at 144.78 208.28 0)
			(effects
				(font
					(size 1.27 1.27)
				)
				(justify left bottom)
				(hide yes)
			)
		)
		(property "Public" "False"
			(at 147.32 208.28 0)
			(effects
				(font
					(size 1.27 1.27)
				)
				(justify left bottom)
				(hide yes)
			)
		)
		(pin "1"
		)
		(pin "2"
		)
		(instances
			(project "artix-dc-scm"
				(path ""
					(reference "C46")
					(unit 1)
				)
			)
		)
	)
	(symbol
		(lib_id "antmicroCapacitorsmisc:C_100n_6V3_0402")
		(at 170.18 218.44 270)
		(mirror x)
		(unit 1)
		(exclude_from_sim no)
		(in_bom yes)
		(on_board yes)
		(dnp no)
		(property "Reference" "C42"
			(at 170.815 213.995 90)
			(effects
				(font
					(size 1.27 1.27)
				)
				(justify left)
			)
		)
		(property "Value" "C_100n_6V3_0402"
			(at 160.02 198.12 0)
			(effects
				(font
					(size 1.27 1.27)
					(thickness 0.15)
				)
				(justify left bottom)
				(hide yes)
			)
		)
		(property "Footprint" "antmicro-footprints:C_0402_1005Metric"
			(at 157.48 198.12 0)
			(effects
				(font
					(size 1.27 1.27)
					(thickness 0.15)
				)
				(justify left bottom)
				(hide yes)
			)
		)
		(property "Datasheet" "https://www.passivecomponent.com/wp-content/uploads/datasheet/WTC_MLCC_General_Purpose.pdf"
			(at 154.94 198.12 0)
			(effects
				(font
					(size 1.27 1.27)
					(thickness 0.15)
				)
				(justify left bottom)
				(hide yes)
			)
		)
		(property "Description" "SMT Multilayer Ceramic Capacitor, 0.1 µF, 6.3 V, 0402 [1005 Metric], ± 10%, X5R, Walsin MLCC"
			(at 170.18 218.44 0)
			(effects
				(font
					(size 1.27 1.27)
				)
				(hide yes)
			)
		)
		(property "Manufacturer" "Walsin"
			(at 149.86 198.12 0)
			(effects
				(font
					(size 1.27 1.27)
					(thickness 0.15)
				)
				(justify left bottom)
				(hide yes)
			)
		)
		(property "MPN" "0402X104K6R3CT"
			(at 152.4 198.12 0)
			(effects
				(font
					(size 1.27 1.27)
					(thickness 0.15)
				)
				(justify left bottom)
				(hide yes)
			)
		)
		(property "Val" "100n"
			(at 170.815 217.805 90)
			(effects
				(font
					(size 1.27 1.27)
					(thickness 0.15)
				)
				(justify left)
			)
		)
		(property "License" "Apache-2.0"
			(at 147.32 198.12 0)
			(effects
				(font
					(size 1.27 1.27)
					(thickness 0.15)
				)
				(justify left bottom)
				(hide yes)
			)
		)
		(property "Author" "Antmicro"
			(at 144.78 198.12 0)
			(effects
				(font
					(size 1.27 1.27)
					(thickness 0.15)
				)
				(justify left bottom)
				(hide yes)
			)
		)
		(property "Voltage" ""
			(at 142.24 198.12 0)
			(effects
				(font
					(size 1.27 1.27)
				)
				(justify left bottom)
				(hide yes)
			)
		)
		(property "Dielectric" ""
			(at 139.7 198.12 0)
			(effects
				(font
					(size 1.27 1.27)
				)
				(justify left bottom)
				(hide yes)
			)
		)
		(property "Public" "False"
			(at 137.16 198.12 0)
			(effects
				(font
					(size 1.27 1.27)
				)
				(justify left bottom)
				(hide yes)
			)
		)
		(pin "1"
		)
		(pin "2"
		)
		(instances
			(project "artix-dc-scm"
				(path ""
					(reference "C42")
					(unit 1)
				)
			)
		)
	)
	(symbol
		(lib_id "antmicroCapacitorsmisc:C_100n_6V3_0402")
		(at 162.56 218.44 270)
		(mirror x)
		(unit 1)
		(exclude_from_sim no)
		(in_bom yes)
		(on_board yes)
		(dnp no)
		(property "Reference" "C44"
			(at 163.195 213.995 90)
			(effects
				(font
					(size 1.27 1.27)
				)
				(justify left)
			)
		)
		(property "Value" "C_100n_6V3_0402"
			(at 152.4 198.12 0)
			(effects
				(font
					(size 1.27 1.27)
					(thickness 0.15)
				)
				(justify left bottom)
				(hide yes)
			)
		)
		(property "Footprint" "antmicro-footprints:C_0402_1005Metric"
			(at 149.86 198.12 0)
			(effects
				(font
					(size 1.27 1.27)
					(thickness 0.15)
				)
				(justify left bottom)
				(hide yes)
			)
		)
		(property "Datasheet" "https://www.passivecomponent.com/wp-content/uploads/datasheet/WTC_MLCC_General_Purpose.pdf"
			(at 147.32 198.12 0)
			(effects
				(font
					(size 1.27 1.27)
					(thickness 0.15)
				)
				(justify left bottom)
				(hide yes)
			)
		)
		(property "Description" "SMT Multilayer Ceramic Capacitor, 0.1 µF, 6.3 V, 0402 [1005 Metric], ± 10%, X5R, Walsin MLCC"
			(at 162.56 218.44 0)
			(effects
				(font
					(size 1.27 1.27)
				)
				(hide yes)
			)
		)
		(property "Manufacturer" "Walsin"
			(at 142.24 198.12 0)
			(effects
				(font
					(size 1.27 1.27)
					(thickness 0.15)
				)
				(justify left bottom)
				(hide yes)
			)
		)
		(property "MPN" "0402X104K6R3CT"
			(at 144.78 198.12 0)
			(effects
				(font
					(size 1.27 1.27)
					(thickness 0.15)
				)
				(justify left bottom)
				(hide yes)
			)
		)
		(property "Val" "100n"
			(at 163.195 217.805 90)
			(effects
				(font
					(size 1.27 1.27)
					(thickness 0.15)
				)
				(justify left)
			)
		)
		(property "License" "Apache-2.0"
			(at 139.7 198.12 0)
			(effects
				(font
					(size 1.27 1.27)
					(thickness 0.15)
				)
				(justify left bottom)
				(hide yes)
			)
		)
		(property "Author" "Antmicro"
			(at 137.16 198.12 0)
			(effects
				(font
					(size 1.27 1.27)
					(thickness 0.15)
				)
				(justify left bottom)
				(hide yes)
			)
		)
		(property "Voltage" ""
			(at 134.62 198.12 0)
			(effects
				(font
					(size 1.27 1.27)
				)
				(justify left bottom)
				(hide yes)
			)
		)
		(property "Dielectric" ""
			(at 132.08 198.12 0)
			(effects
				(font
					(size 1.27 1.27)
				)
				(justify left bottom)
				(hide yes)
			)
		)
		(property "Public" "False"
			(at 129.54 198.12 0)
			(effects
				(font
					(size 1.27 1.27)
				)
				(justify left bottom)
				(hide yes)
			)
		)
		(pin "1"
		)
		(pin "2"
		)
		(instances
			(project "artix-dc-scm"
				(path ""
					(reference "C44")
					(unit 1)
				)
			)
		)
	)
	(symbol
		(lib_id "antmicroCapacitorsmisc:C_100n_6V3_0402")
		(at 114.3 92.71 270)
		(unit 1)
		(exclude_from_sim no)
		(in_bom yes)
		(on_board yes)
		(dnp no)
		(property "Reference" "C63"
			(at 114.935 93.345 90)
			(effects
				(font
					(size 1.27 1.27)
				)
				(justify left)
			)
		)
		(property "Value" "C_100n_6V3_0402"
			(at 104.14 113.03 0)
			(effects
				(font
					(size 1.27 1.27)
					(thickness 0.15)
				)
				(justify left bottom)
				(hide yes)
			)
		)
		(property "Footprint" "antmicro-footprints:C_0402_1005Metric"
			(at 101.6 113.03 0)
			(effects
				(font
					(size 1.27 1.27)
					(thickness 0.15)
				)
				(justify left bottom)
				(hide yes)
			)
		)
		(property "Datasheet" "https://www.passivecomponent.com/wp-content/uploads/datasheet/WTC_MLCC_General_Purpose.pdf"
			(at 99.06 113.03 0)
			(effects
				(font
					(size 1.27 1.27)
					(thickness 0.15)
				)
				(justify left bottom)
				(hide yes)
			)
		)
		(property "Description" "SMT Multilayer Ceramic Capacitor, 0.1 µF, 6.3 V, 0402 [1005 Metric], ± 10%, X5R, Walsin MLCC"
			(at 114.3 92.71 0)
			(effects
				(font
					(size 1.27 1.27)
				)
				(hide yes)
			)
		)
		(property "Manufacturer" "Walsin"
			(at 93.98 113.03 0)
			(effects
				(font
					(size 1.27 1.27)
					(thickness 0.15)
				)
				(justify left bottom)
				(hide yes)
			)
		)
		(property "MPN" "0402X104K6R3CT"
			(at 96.52 113.03 0)
			(effects
				(font
					(size 1.27 1.27)
					(thickness 0.15)
				)
				(justify left bottom)
				(hide yes)
			)
		)
		(property "Val" "100n"
			(at 114.935 97.155 90)
			(effects
				(font
					(size 1.27 1.27)
					(thickness 0.15)
				)
				(justify left)
			)
		)
		(property "License" "Apache-2.0"
			(at 91.44 113.03 0)
			(effects
				(font
					(size 1.27 1.27)
					(thickness 0.15)
				)
				(justify left bottom)
				(hide yes)
			)
		)
		(property "Author" "Antmicro"
			(at 88.9 113.03 0)
			(effects
				(font
					(size 1.27 1.27)
					(thickness 0.15)
				)
				(justify left bottom)
				(hide yes)
			)
		)
		(property "Voltage" ""
			(at 86.36 113.03 0)
			(effects
				(font
					(size 1.27 1.27)
				)
				(justify left bottom)
				(hide yes)
			)
		)
		(property "Dielectric" ""
			(at 83.82 113.03 0)
			(effects
				(font
					(size 1.27 1.27)
				)
				(justify left bottom)
				(hide yes)
			)
		)
		(property "Public" "False"
			(at 81.28 113.03 0)
			(effects
				(font
					(size 1.27 1.27)
				)
				(justify left bottom)
				(hide yes)
			)
		)
		(pin "1"
		)
		(pin "2"
		)
		(instances
			(project "artix-dc-scm"
				(path ""
					(reference "C63")
					(unit 1)
				)
			)
		)
	)
	(symbol
		(lib_id "antmicroPMICVoltageRegulatorsDCDCSwitchingControllers:TPS51200DRCT")
		(at 129.54 195.58 0)
		(unit 1)
		(exclude_from_sim no)
		(in_bom yes)
		(on_board yes)
		(dnp no)
		(fields_autoplaced yes)
		(property "Reference" "U8"
			(at 139.7 187.96 0)
			(effects
				(font
					(size 1.27 1.27)
				)
			)
		)
		(property "Value" "TPS51200DRCT"
			(at 165.1 203.2 0)
			(effects
				(font
					(size 1.27 1.27)
					(thickness 0.15)
				)
				(justify left bottom)
				(hide yes)
			)
		)
		(property "Footprint" "antmicro-footprints:VSON-10-1EP_3x3mm"
			(at 165.1 205.74 0)
			(effects
				(font
					(size 1.27 1.27)
					(thickness 0.15)
				)
				(justify left bottom)
				(hide yes)
			)
		)
		(property "Datasheet" "https://www.ti.com/lit/ds/symlink/tps51200.pdf?ts=1685420125657"
			(at 165.1 208.28 0)
			(effects
				(font
					(size 1.27 1.27)
					(thickness 0.15)
				)
				(justify left bottom)
				(hide yes)
			)
		)
		(property "Description" "Fixed LDO Voltage Regulator, 2.375 V to 3.5 V, 0.8 V Dropout, 1.25 V / 3 A out, VSON-10"
			(at 129.54 195.58 0)
			(effects
				(font
					(size 1.27 1.27)
				)
				(hide yes)
			)
		)
		(property "MPN" "TPS51200DRCT"
			(at 139.7 190.5 0)
			(effects
				(font
					(size 1.27 1.27)
					(thickness 0.15)
				)
			)
		)
		(property "Manufacturer" "Texas Instruments"
			(at 165.1 210.82 0)
			(effects
				(font
					(size 1.27 1.27)
					(thickness 0.15)
				)
				(justify left bottom)
				(hide yes)
			)
		)
		(property "Author" "Antmicro"
			(at 165.1 215.9 0)
			(effects
				(font
					(size 1.27 1.27)
					(thickness 0.15)
				)
				(justify left bottom)
				(hide yes)
			)
		)
		(property "License" "Apache-2.0"
			(at 165.1 218.44 0)
			(effects
				(font
					(size 1.27 1.27)
					(thickness 0.15)
				)
				(justify left bottom)
				(hide yes)
			)
		)
		(property "VSD_class" "TPS51200"
			(at 165.1 213.36 0)
			(effects
				(font
					(size 1.27 1.27)
					(thickness 0.15)
				)
				(justify left bottom)
				(hide yes)
			)
		)
		(pin "1"
		)
		(pin "10"
		)
		(pin "11"
		)
		(pin "2"
		)
		(pin "3"
		)
		(pin "4"
		)
		(pin "5"
		)
		(pin "6"
		)
		(pin "7"
		)
		(pin "8"
		)
		(pin "9"
		)
		(instances
			(project "artix-dc-scm"
				(path ""
					(reference "U8")
					(unit 1)
				)
			)
		)
	)
	(symbol
		(lib_id "antmicroMemory:AS4C256M16D3")
		(at 200.66 59.69 0)
		(unit 1)
		(exclude_from_sim no)
		(in_bom yes)
		(on_board yes)
		(dnp no)
		(fields_autoplaced yes)
		(property "Reference" "U7"
			(at 218.44 52.705 0)
			(effects
				(font
					(size 1.27 1.27)
					(thickness 0.15)
				)
			)
		)
		(property "Value" "AS4C256M16D3"
			(at 251.46 62.23 0)
			(effects
				(font
					(size 1.27 1.27)
					(thickness 0.15)
				)
				(justify left bottom)
				(hide yes)
			)
		)
		(property "Footprint" "antmicro-footprints:BGA-96-48_7.5x13.5mm_Layout9x16_P0.8mm"
			(at 251.46 64.77 0)
			(effects
				(font
					(size 1.27 1.27)
					(thickness 0.15)
				)
				(justify left bottom)
				(hide yes)
			)
		)
		(property "Datasheet" "https://www.alliancememory.com/wp-content/uploads/AllianceMemory_4G_DDR3L_AS4C256M16D3LC_March2020_Rev1.0.pdf"
			(at 251.46 67.31 0)
			(effects
				(font
					(size 1.27 1.27)
					(thickness 0.15)
				)
				(justify left bottom)
				(hide yes)
			)
		)
		(property "Description" "SDRAM - DDR3 Memory IC 4Gbit Parallel 800 MHz 20 ns 96-FBGA (9x13)"
			(at 200.66 59.69 0)
			(effects
				(font
					(size 1.27 1.27)
				)
				(hide yes)
			)
		)
		(property "Manufacturer" "Alliance Memory"
			(at 251.46 69.85 0)
			(effects
				(font
					(size 1.27 1.27)
					(thickness 0.15)
				)
				(justify left bottom)
				(hide yes)
			)
		)
		(property "MPN" "AS4C256M16D3LC-12BCN"
			(at 218.44 55.245 0)
			(effects
				(font
					(size 1.27 1.27)
					(thickness 0.15)
				)
			)
		)
		(property "Author" "Antmicro"
			(at 251.46 74.93 0)
			(effects
				(font
					(size 1.27 1.27)
					(thickness 0.15)
				)
				(justify left bottom)
				(hide yes)
			)
		)
		(property "License" "Apache-2.0"
			(at 251.46 77.47 0)
			(effects
				(font
					(size 1.27 1.27)
					(thickness 0.15)
				)
				(justify left bottom)
				(hide yes)
			)
		)
		(pin "D7"
		)
		(pin "H1"
		)
		(pin "R1"
		)
		(pin "B8"
		)
		(pin "T2"
		)
		(pin "M8"
		)
		(pin "H8"
		)
		(pin "F9"
		)
		(pin "G2"
		)
		(pin "N8"
		)
		(pin "G3"
		)
		(pin "J1"
		)
		(pin "D8"
		)
		(pin "K7"
		)
		(pin "H7"
		)
		(pin "P3"
		)
		(pin "C9"
		)
		(pin "H2"
		)
		(pin "F8"
		)
		(pin "P7"
		)
		(pin "D2"
		)
		(pin "M7"
		)
		(pin "N3"
		)
		(pin "R3"
		)
		(pin "E9"
		)
		(pin "E3"
		)
		(pin "B3"
		)
		(pin "C3"
		)
		(pin "H9"
		)
		(pin "N9"
		)
		(pin "F3"
		)
		(pin "G9"
		)
		(pin "R8"
		)
		(pin "P8"
		)
		(pin "B9"
		)
		(pin "C8"
		)
		(pin "L2"
		)
		(pin "M1"
		)
		(pin "E1"
		)
		(pin "J2"
		)
		(pin "L3"
		)
		(pin "E8"
		)
		(pin "L7"
		)
		(pin "T1"
		)
		(pin "K3"
		)
		(pin "J3"
		)
		(pin "C2"
		)
		(pin "M3"
		)
		(pin "G8"
		)
		(pin "F7"
		)
		(pin "K1"
		)
		(pin "T7"
		)
		(pin "M9"
		)
		(pin "J7"
		)
		(pin "L8"
		)
		(pin "A9"
		)
		(pin "C1"
		)
		(pin "R2"
		)
		(pin "E2"
		)
		(pin "T3"
		)
		(pin "T8"
		)
		(pin "A2"
		)
		(pin "C7"
		)
		(pin "T9"
		)
		(pin "J8"
		)
		(pin "R7"
		)
		(pin "B7"
		)
		(pin "A7"
		)
		(pin "E7"
		)
		(pin "P1"
		)
		(pin "D9"
		)
		(pin "N1"
		)
		(pin "K2"
		)
		(pin "B2"
		)
		(pin "K8"
		)
		(pin "G7"
		)
		(pin "N2"
		)
		(pin "F2"
		)
		(pin "L1"
		)
		(pin "A8"
		)
		(pin "P9"
		)
		(pin "A1"
		)
		(pin "K9"
		)
		(pin "H3"
		)
		(pin "F1"
		)
		(pin "P2"
		)
		(pin "R9"
		)
		(pin "J9"
		)
		(pin "G1"
		)
		(pin "D3"
		)
		(pin "B1"
		)
		(pin "N7"
		)
		(pin "D1"
		)
		(pin "A3"
		)
		(pin "M2"
		)
		(pin "L9"
		)
		(instances
			(project ""
				(path ""
					(reference "U7")
					(unit 1)
				)
			)
		)
	)
	(symbol
		(lib_id "antmicropower:GND")
		(at 238.76 147.32 0)
		(unit 1)
		(exclude_from_sim no)
		(in_bom yes)
		(on_board yes)
		(dnp no)
		(property "Reference" "#PWR0282"
			(at 238.76 153.67 0)
			(effects
				(font
					(size 1.27 1.27)
				)
				(hide yes)
			)
		)
		(property "Value" "GND"
			(at 238.76 151.13 0)
			(effects
				(font
					(size 1.27 1.27)
				)
			)
		)
		(property "Footprint" ""
			(at 238.76 147.32 0)
			(effects
				(font
					(size 1.27 1.27)
				)
				(hide yes)
			)
		)
		(property "Datasheet" ""
			(at 238.76 147.32 0)
			(effects
				(font
					(size 1.27 1.27)
				)
				(hide yes)
			)
		)
		(property "Description" ""
			(at 238.76 147.32 0)
			(effects
				(font
					(size 1.27 1.27)
				)
				(hide yes)
			)
		)
		(property "Author" "Antmicro"
			(at 247.65 154.94 0)
			(effects
				(font
					(size 1.27 1.27)
					(thickness 0.15)
				)
				(justify left bottom)
				(hide yes)
			)
		)
		(property "License" "Apache-2.0"
			(at 247.65 157.48 0)
			(effects
				(font
					(size 1.27 1.27)
					(thickness 0.15)
				)
				(justify left bottom)
				(hide yes)
			)
		)
		(pin "1"
		)
		(instances
			(project "artix-dc-scm"
				(path ""
					(reference "#PWR0282")
					(unit 1)
				)
			)
		)
	)
)
